FILE_TYPE = MACRO_DRAWING;
SET COLOR_WIRE YELLOW;
SET COLOR_PROP MONO;
SET COLOR_DOT WHITE;
SET COLOR_ARC YELLOW;
SET COLOR_BODY GREEN;
SET COLOR_NOTE MONO;
SET PROP_DISPLAY VALUE;
SET PAGE_NUMBER P203;
FORCEADD CAP..1
(-6350 4175);
FORCEPROP 1 LAST LOCATION C6P24
J 0
(-6300 4275);
DISPLAY 0.617021 (-6300 4275);
PAINT AQUA (-6300 4275);
FORCEPROP 1 LAST VALUE 10UF
J 0
(-6300 4225);
DISPLAY 0.617021 (-6300 4225);
PAINT SKYBLUE (-6300 4225);
FORCEPROP 1 LAST VOLTAGE 16V
J 0
(-6300 4175);
DISPLAY 0.617021 (-6300 4175);
PAINT SKYBLUE (-6300 4175);
FORCEPROP 1 LASTPIN (-6350 4275) $PN 1
J 0
(-6340 4255);
DISPLAY 0.617021 (-6340 4255);
PAINT ORANGE (-6340 4255);
FORCEPROP 1 LAST PACK_TYPE 0805
J 0
(-6300 3975);
DISPLAY 0.617021 (-6300 3975);
PAINT SKYBLUE (-6300 3975);
FORCEPROP 1 LASTPIN (-6350 4075) $PN 2
J 0
(-6340 4055);
DISPLAY 0.617021 (-6340 4055);
PAINT ORANGE (-6340 4055);
FORCEPROP 1 LAST MATERIAL X6S
J 0
(-6300 4075);
DISPLAY 0.617021 (-6300 4075);
PAINT SKYBLUE (-6300 4075);
FORCEPROP 1 LAST PART_NUMBER C95333-007
J 0
(-6300 4025);
DISPLAY 0.617021 (-6300 4025);
PAINT BLUE (-6300 4025);
FORCEPROP 1 LAST TOLERANCE 10%
J 0
(-6300 4125);
DISPLAY 0.617021 (-6300 4125);
PAINT SKYBLUE (-6300 4125);
FORCEPROP 2 LAST SEC 1
J 0
(-6300 4375);
DISPLAY 0.680851 (-6300 4375);
PAINT MONO (-6300 4375);
DISPLAY INVISIBLE (-6300 4375);
FORCEPROP 2 LAST SEC_TYPE 0805
J 0
(-6300 4375);
DISPLAY 1.021277 (-6300 4375);
PAINT ORANGE (-6300 4375);
DISPLAY INVISIBLE (-6300 4375);
FORCEPROP 2 LAST ROOM PVCCIN_CPU0_PWR_VR
J 0
(-6300 4325);
DISPLAY 1.361702 (-6300 4325);
PAINT ORANGE (-6300 4325);
DISPLAY INVISIBLE (-6300 4325);
FORCEPROP 1 LAST PATH I1
J 0
(-6300 4325);
DISPLAY 0.978723 (-6300 4325);
PAINT WHITE (-6300 4325);
DISPLAY INVISIBLE (-6300 4325);
FORCEPROP 2 LAST CDS_LIB mstr_discrete
J 0
(-6350 4175);
PAINT ORANGE (-6350 4175);
DISPLAY INVISIBLE (-6350 4175);
FORCEADD GND..1
(-1975 3775);
FORCEPROP 3 LASTPIN (-1975 3825) SIG_NAME GND\g
J 0
(-1965 3835);
DISPLAY 0.659574 (-1965 3835);
PAINT MONO (-1965 3835);
DISPLAY INVISIBLE (-1965 3835);
FORCEPROP 1 LAST HDL_POWER GND
J 0
(-1975 3925);
DISPLAY 1.170213 (-1975 3925);
PAINT GREEN (-1975 3925);
DISPLAY INVISIBLE (-1975 3925);
FORCEPROP 1 LAST BODY_TYPE PLUMBING
J 0
(-2020 3732);
DISPLAY 0.340426 (-2020 3732);
PAINT GREEN (-2020 3732);
DISPLAY INVISIBLE (-2020 3732);
FORCEPROP 2 LAST CDS_LIB mstr_symbols
J 0
(-1975 3775);
PAINT MONO (-1975 3775);
DISPLAY INVISIBLE (-1975 3775);
FORCEPROP 1 LAST PATH I100
J 0
(-1900 3775);
DISPLAY 0.872340 (-1900 3775);
PAINT AQUA (-1900 3775);
DISPLAY INVISIBLE (-1900 3775);
FORCEPROP 1 LAST SIZE 1B
J 0
(-1900 3725);
DISPLAY 1.170213 (-1900 3725);
PAINT AQUA (-1900 3725);
DISPLAY INVISIBLE (-1900 3725);
FORCEPROP 1 LAST VOLTAGE 0
J 0
(-1975 3775);
PAINT SKYBLUE (-1975 3775);
DISPLAY INVISIBLE (-1975 3775);
FORCEPROP 2 LAST ROOM VDDQ_KLM_PWR_VR
J 0
(-2550 3850);
DISPLAY 1.361702 (-2550 3850);
PAINT ORANGE (-2550 3850);
DISPLAY INVISIBLE (-2550 3850);
FORCEADD GND..1
(-1950 3000);
FORCEPROP 3 LASTPIN (-1950 3050) SIG_NAME GND\g
J 0
(-1940 3060);
DISPLAY 0.659574 (-1940 3060);
PAINT MONO (-1940 3060);
DISPLAY INVISIBLE (-1940 3060);
FORCEPROP 1 LAST HDL_POWER GND
J 0
(-1950 3150);
DISPLAY 1.723404 (-1950 3150);
PAINT GREEN (-1950 3150);
DISPLAY INVISIBLE (-1950 3150);
FORCEPROP 1 LAST BODY_TYPE PLUMBING
J 0
(-1995 2957);
DISPLAY 0.340426 (-1995 2957);
PAINT GREEN (-1995 2957);
DISPLAY INVISIBLE (-1995 2957);
FORCEPROP 2 LAST CDS_LIB mstr_symbols
J 0
(-1950 3000);
PAINT MONO (-1950 3000);
DISPLAY INVISIBLE (-1950 3000);
FORCEPROP 1 LAST PATH I103
J 0
(-1875 3000);
DISPLAY 0.872340 (-1875 3000);
PAINT AQUA (-1875 3000);
DISPLAY INVISIBLE (-1875 3000);
FORCEPROP 2 LAST ROOM PVCCIN_CPU0_PWR_VR
J 0
(-2500 3075);
DISPLAY 1.936170 (-2500 3075);
PAINT ORANGE (-2500 3075);
DISPLAY INVISIBLE (-2500 3075);
FORCEPROP 2 LAST BOM_COST PROC_VRD_VCCIN_CPU0
J 0
(-2325 3075);
DISPLAY 1.446809 (-2325 3075);
PAINT MONO (-2325 3075);
DISPLAY INVISIBLE (-2325 3075);
FORCEPROP 1 LAST VOLTAGE 0
J 0
(-1950 3000);
PAINT SKYBLUE (-1950 3000);
DISPLAY INVISIBLE (-1950 3000);
FORCEPROP 1 LAST SIZE 1B
J 0
(-1875 2950);
DISPLAY 1.723404 (-1875 2950);
PAINT GREEN (-1875 2950);
DISPLAY INVISIBLE (-1875 2950);
FORCEADD GND..1
(-1975 350);
FORCEPROP 3 LASTPIN (-1975 400) SIG_NAME GND\g
J 0
(-1965 410);
DISPLAY 0.659574 (-1965 410);
PAINT MONO (-1965 410);
DISPLAY INVISIBLE (-1965 410);
FORCEPROP 1 LAST HDL_POWER GND
J 0
(-1975 500);
DISPLAY 1.723404 (-1975 500);
PAINT GREEN (-1975 500);
DISPLAY INVISIBLE (-1975 500);
FORCEPROP 1 LAST BODY_TYPE PLUMBING
J 0
(-2020 307);
DISPLAY 0.340426 (-2020 307);
PAINT GREEN (-2020 307);
DISPLAY INVISIBLE (-2020 307);
FORCEPROP 2 LAST CDS_LIB mstr_symbols
J 0
(-1975 350);
PAINT MONO (-1975 350);
DISPLAY INVISIBLE (-1975 350);
FORCEPROP 1 LAST PATH I104
J 0
(-1900 350);
DISPLAY 0.872340 (-1900 350);
PAINT AQUA (-1900 350);
DISPLAY INVISIBLE (-1900 350);
FORCEPROP 1 LAST SIZE 1B
J 0
(-1900 300);
DISPLAY 1.723404 (-1900 300);
PAINT GREEN (-1900 300);
DISPLAY INVISIBLE (-1900 300);
FORCEPROP 1 LAST VOLTAGE 0
J 0
(-1975 350);
PAINT SKYBLUE (-1975 350);
DISPLAY INVISIBLE (-1975 350);
FORCEPROP 2 LAST BOM_COST PROC_VRD_VCCIN_CPU0
J 0
(-2350 425);
DISPLAY 1.446809 (-2350 425);
PAINT MONO (-2350 425);
DISPLAY INVISIBLE (-2350 425);
FORCEPROP 2 LAST ROOM PVCCIN_CPU0_PWR_VR
J 0
(-2525 425);
DISPLAY 1.936170 (-2525 425);
PAINT ORANGE (-2525 425);
DISPLAY INVISIBLE (-2525 425);
FORCEADD GND..1
(-1925 1075);
FORCEPROP 3 LASTPIN (-1925 1125) SIG_NAME GND\g
J 0
(-1915 1135);
DISPLAY 0.659574 (-1915 1135);
PAINT MONO (-1915 1135);
DISPLAY INVISIBLE (-1915 1135);
FORCEPROP 1 LAST HDL_POWER GND
J 0
(-1925 1225);
DISPLAY 1.170213 (-1925 1225);
PAINT GREEN (-1925 1225);
DISPLAY INVISIBLE (-1925 1225);
FORCEPROP 1 LAST BODY_TYPE PLUMBING
J 0
(-1970 1032);
DISPLAY 0.340426 (-1970 1032);
PAINT GREEN (-1970 1032);
DISPLAY INVISIBLE (-1970 1032);
FORCEPROP 1 LAST SIZE 1B
J 0
(-1850 1025);
DISPLAY 1.170213 (-1850 1025);
PAINT AQUA (-1850 1025);
DISPLAY INVISIBLE (-1850 1025);
FORCEPROP 1 LAST VOLTAGE 0
J 0
(-1925 1075);
PAINT SKYBLUE (-1925 1075);
DISPLAY INVISIBLE (-1925 1075);
FORCEPROP 2 LAST ROOM VDDQ_KLM_PWR_VR
J 0
(-2500 1150);
DISPLAY 1.361702 (-2500 1150);
PAINT ORANGE (-2500 1150);
DISPLAY INVISIBLE (-2500 1150);
FORCEPROP 1 LAST PATH I107
J 0
(-1850 1075);
DISPLAY 0.872340 (-1850 1075);
PAINT AQUA (-1850 1075);
DISPLAY INVISIBLE (-1850 1075);
FORCEPROP 2 LAST CDS_LIB mstr_symbols
J 0
(-1925 1075);
PAINT MONO (-1925 1075);
DISPLAY INVISIBLE (-1925 1075);
FORCEADD CAP..1
(-1925 1275);
FORCEPROP 1 LAST LOCATION CT42
J 0
(-2075 1275);
DISPLAY 0.617021 (-2075 1275);
PAINT AQUA (-2075 1275);
FORCEPROP 1 LASTPIN (-1925 1375) $PN 1
J 0
(-1915 1355);
DISPLAY 0.787234 (-1915 1355);
PAINT ORANGE (-1915 1355);
FORCEPROP 1 LASTPIN (-1925 1175) $PN 2
J 0
(-1915 1155);
DISPLAY 0.787234 (-1915 1155);
PAINT ORANGE (-1915 1155);
FORCEPROP 0 LAST POP NOPOP
J 0
(-1700 1325);
DISPLAY 1.021277 (-1700 1325);
PAINT RED (-1700 1325);
FORCEPROP 1 LAST VALUE 1000PF
J 0
(-1875 1325);
DISPLAY 0.617021 (-1875 1325);
PAINT SKYBLUE (-1875 1325);
FORCEPROP 1 LAST VOLTAGE 50V
J 0
(-1875 1275);
DISPLAY 0.617021 (-1875 1275);
PAINT SKYBLUE (-1875 1275);
FORCEPROP 1 LAST TOLERANCE 10%
J 0
(-1875 1225);
DISPLAY 0.617021 (-1875 1225);
PAINT SKYBLUE (-1875 1225);
FORCEPROP 1 LAST MATERIAL X7R
J 0
(-1875 1175);
DISPLAY 0.617021 (-1875 1175);
PAINT SKYBLUE (-1875 1175);
FORCEPROP 1 LAST PART_NUMBER A36096-046
J 0
(-1875 1125);
DISPLAY 0.617021 (-1875 1125);
PAINT BLUE (-1875 1125);
FORCEPROP 1 LAST PACK_TYPE 0402LF
J 0
(-1875 1075);
DISPLAY 0.617021 (-1875 1075);
PAINT SKYBLUE (-1875 1075);
FORCEPROP 2 LAST SEC_TYPE 0402LF
J 0
(-1875 1475);
DISPLAY 1.021277 (-1875 1475);
PAINT ORANGE (-1875 1475);
DISPLAY INVISIBLE (-1875 1475);
FORCEPROP 2 LAST SEC 1
J 0
(-1875 1475);
DISPLAY 0.680851 (-1875 1475);
PAINT MONO (-1875 1475);
DISPLAY INVISIBLE (-1875 1475);
FORCEPROP 2 LAST CDS_LIB mstr_discrete
J 0
(-1925 1275);
PAINT MONO (-1925 1275);
DISPLAY INVISIBLE (-1925 1275);
FORCEPROP 1 LAST PATH I108
J 0
(-1875 1425);
DISPLAY 0.978723 (-1875 1425);
PAINT WHITE (-1875 1425);
DISPLAY INVISIBLE (-1875 1425);
FORCEPROP 0 LAST ROOM VDDQ_KLM_PWR_VR
J 0
(-1875 1475);
DISPLAY 1.021277 (-1875 1475);
PAINT ORANGE (-1875 1475);
DISPLAY INVISIBLE (-1875 1475);
FORCEADD PVCCIN_CPU0..1
(-450 1025);
FORCEPROP 3 LASTPIN (-450 975) SIG_NAME PVCCIN_CPU0\g
J 0
(-440 985);
DISPLAY 0.659574 (-440 985);
PAINT MONO (-440 985);
DISPLAY INVISIBLE (-440 985);
FORCEPROP 1 LAST PATH I109
J 0
(-400 1050);
DISPLAY 0.872340 (-400 1050);
PAINT AQUA (-400 1050);
DISPLAY INVISIBLE (-400 1050);
FORCEPROP 2 LAST CDS_LIB mstr_symbols
J 0
(-450 1025);
PAINT ORANGE (-450 1025);
DISPLAY INVISIBLE (-450 1025);
FORCEPROP 1 LAST VOLTAGE 2.0V
J 0
(-495 982);
DISPLAY 0.340426 (-495 982);
PAINT SKYBLUE (-495 982);
DISPLAY INVISIBLE (-495 982);
FORCEPROP 1 LAST BODY_TYPE PLUMBING
J 0
(-495 982);
DISPLAY 0.340426 (-495 982);
PAINT GREEN (-495 982);
DISPLAY INVISIBLE (-495 982);
FORCEPROP 1 LAST HDL_POWER PVCCIN_CPU0
J 1
(-450 1075);
DISPLAY 0.872340 (-450 1075);
PAINT GREEN (-450 1075);
DISPLAY INVISIBLE (-450 1075);
FORCEADD CAP..1
(-1950 3500);
FORCEPROP 0 LAST POP NOPOP
J 0
(-2150 3525);
DISPLAY 0.808511 (-2150 3525);
PAINT RED (-2150 3525);
FORCEPROP 1 LASTPIN (-1950 3400) $PN 2
J 0
(-1940 3380);
DISPLAY 0.787234 (-1940 3380);
PAINT ORANGE (-1940 3380);
FORCEPROP 1 LASTPIN (-1950 3600) $PN 1
J 0
(-1940 3580);
DISPLAY 0.787234 (-1940 3580);
PAINT ORANGE (-1940 3580);
FORCEPROP 1 LAST MATERIAL X7R
J 0
(-1775 3450);
DISPLAY 0.617021 (-1775 3450);
PAINT SKYBLUE (-1775 3450);
FORCEPROP 1 LAST PART_NUMBER A36096-046
J 0
(-1750 3500);
DISPLAY 0.617021 (-1750 3500);
PAINT BLUE (-1750 3500);
FORCEPROP 1 LAST VALUE 1000PF
J 0
(-1775 3550);
DISPLAY 0.617021 (-1775 3550);
PAINT SKYBLUE (-1775 3550);
FORCEPROP 1 LAST LOCATION CT38
J 0
(-1900 3550);
DISPLAY 0.617021 (-1900 3550);
PAINT AQUA (-1900 3550);
FORCEPROP 1 LAST VOLTAGE 50V
J 0
(-1900 3500);
DISPLAY 0.617021 (-1900 3500);
PAINT SKYBLUE (-1900 3500);
FORCEPROP 1 LAST PACK_TYPE 0402LF
J 0
(-1650 3450);
DISPLAY 0.617021 (-1650 3450);
PAINT SKYBLUE (-1650 3450);
FORCEPROP 1 LAST TOLERANCE 10%
J 0
(-1900 3450);
DISPLAY 0.617021 (-1900 3450);
PAINT SKYBLUE (-1900 3450);
FORCEPROP 2 LAST SEC_TYPE 0402LF
J 0
(-1900 3700);
DISPLAY 1.021277 (-1900 3700);
PAINT ORANGE (-1900 3700);
DISPLAY INVISIBLE (-1900 3700);
FORCEPROP 0 LAST SEC 1
J 0
(-1900 3650);
DISPLAY 0.680851 (-1900 3650);
PAINT MONO (-1900 3650);
DISPLAY INVISIBLE (-1900 3650);
FORCEPROP 0 LAST ROOM VDDQ_KLM_PWR_VR
J 0
(-1900 3700);
DISPLAY 1.021277 (-1900 3700);
PAINT ORANGE (-1900 3700);
DISPLAY INVISIBLE (-1900 3700);
FORCEPROP 1 LAST PATH I118
J 0
(-1900 3650);
DISPLAY 0.978723 (-1900 3650);
PAINT WHITE (-1900 3650);
DISPLAY INVISIBLE (-1900 3650);
FORCEPROP 2 LAST CDS_LIB mstr_discrete
J 0
(-1950 3500);
PAINT MONO (-1950 3500);
DISPLAY INVISIBLE (-1950 3500);
FORCEADD CAP..1
(-1975 800);
FORCEPROP 1 LAST PACK_TYPE 0402LF
J 0
(-1675 800);
DISPLAY 0.617021 (-1675 800);
PAINT SKYBLUE (-1675 800);
FORCEPROP 1 LAST PART_NUMBER A36096-046
J 0
(-1800 750);
DISPLAY 0.617021 (-1800 750);
PAINT BLUE (-1800 750);
FORCEPROP 1 LAST TOLERANCE 10%
J 0
(-1825 800);
DISPLAY 0.617021 (-1825 800);
PAINT SKYBLUE (-1825 800);
FORCEPROP 1 LAST MATERIAL X7R
J 0
(-1925 750);
DISPLAY 0.617021 (-1925 750);
PAINT SKYBLUE (-1925 750);
FORCEPROP 1 LASTPIN (-1975 700) $PN 2
J 0
(-1965 680);
DISPLAY 0.787234 (-1965 680);
PAINT ORANGE (-1965 680);
FORCEPROP 1 LAST VOLTAGE 50V
J 0
(-1925 800);
DISPLAY 0.617021 (-1925 800);
PAINT SKYBLUE (-1925 800);
FORCEPROP 0 LAST POP NOPOP
J 0
(-1575 850);
DISPLAY 0.808511 (-1575 850);
PAINT RED (-1575 850);
FORCEPROP 1 LASTPIN (-1975 900) $PN 1
J 0
(-1965 880);
DISPLAY 0.787234 (-1965 880);
PAINT ORANGE (-1965 880);
FORCEPROP 1 LAST LOCATION CT41
J 0
(-1925 850);
DISPLAY 0.617021 (-1925 850);
PAINT AQUA (-1925 850);
FORCEPROP 1 LAST VALUE 1000PF
J 0
(-1775 850);
DISPLAY 0.617021 (-1775 850);
PAINT SKYBLUE (-1775 850);
FORCEPROP 2 LAST SEC_TYPE 0402LF
J 0
(-1925 1000);
DISPLAY 1.021277 (-1925 1000);
PAINT ORANGE (-1925 1000);
DISPLAY INVISIBLE (-1925 1000);
FORCEPROP 0 LAST SEC 1
J 0
(-1925 950);
DISPLAY 0.680851 (-1925 950);
PAINT MONO (-1925 950);
DISPLAY INVISIBLE (-1925 950);
FORCEPROP 0 LAST ROOM VDDQ_KLM_PWR_VR
J 0
(-1925 1000);
DISPLAY 1.021277 (-1925 1000);
PAINT ORANGE (-1925 1000);
DISPLAY INVISIBLE (-1925 1000);
FORCEPROP 1 LAST PATH I119
J 0
(-1925 950);
DISPLAY 0.978723 (-1925 950);
PAINT WHITE (-1925 950);
DISPLAY INVISIBLE (-1925 950);
FORCEPROP 2 LAST CDS_LIB mstr_discrete
J 0
(-1975 800);
PAINT MONO (-1975 800);
DISPLAY INVISIBLE (-1975 800);
FORCEADD PVCCIN_CPU0..1
(-500 3750);
FORCEPROP 3 LASTPIN (-500 3700) SIG_NAME PVCCIN_CPU0\g
J 0
(-490 3710);
DISPLAY 0.659574 (-490 3710);
PAINT MONO (-490 3710);
DISPLAY INVISIBLE (-490 3710);
FORCEPROP 1 LAST VOLTAGE 2.0V
J 0
(-545 3707);
DISPLAY 0.340426 (-545 3707);
PAINT SKYBLUE (-545 3707);
DISPLAY INVISIBLE (-545 3707);
FORCEPROP 1 LAST PATH I12
J 0
(-450 3775);
DISPLAY 0.872340 (-450 3775);
PAINT AQUA (-450 3775);
DISPLAY INVISIBLE (-450 3775);
FORCEPROP 2 LAST CDS_LIB mstr_symbols
J 0
(-500 3750);
PAINT ORANGE (-500 3750);
DISPLAY INVISIBLE (-500 3750);
FORCEPROP 1 LAST BODY_TYPE PLUMBING
J 0
(-545 3707);
DISPLAY 0.340426 (-545 3707);
PAINT GREEN (-545 3707);
DISPLAY INVISIBLE (-545 3707);
FORCEPROP 1 LAST HDL_POWER PVCCIN_CPU0
J 1
(-500 3800);
DISPLAY 0.872340 (-500 3800);
PAINT GREEN (-500 3800);
DISPLAY INVISIBLE (-500 3800);
FORCEADD RES..1
(-4725 3725);
FORCEPROP 1 LAST PACK_TYPE 0603
J 0
(-4650 3675);
DISPLAY 0.617021 (-4650 3675);
PAINT SKYBLUE (-4650 3675);
FORCEPROP 1 LAST LOCATION RT25
J 0
(-4825 3575);
DISPLAY 0.617021 (-4825 3575);
PAINT AQUA (-4825 3575);
FORCEPROP 1 LAST PART_NUMBER G22178-002
J 0
(-4825 3625);
DISPLAY 0.617021 (-4825 3625);
PAINT BLUE (-4825 3625);
FORCEPROP 1 LAST VALUE 0
J 2
(-4775 3675);
DISPLAY 0.617021 (-4775 3675);
PAINT SKYBLUE (-4775 3675);
FORCEPROP 1 LASTPIN (-4825 3725) $PN 1
J 0
(-4813 3737);
DISPLAY 0.787234 (-4813 3737);
PAINT ORANGE (-4813 3737);
FORCEPROP 0 LAST SEC 1
J 0
(-4775 3925);
DISPLAY 0.680851 (-4775 3925);
PAINT MONO (-4775 3925);
FORCEPROP 1 LASTPIN (-4625 3725) $PN 2
J 0
(-4663 3737);
DISPLAY 0.787234 (-4663 3737);
PAINT ORANGE (-4663 3737);
FORCEPROP 1 LAST MATERIAL CHIP
J 0
(-4675 3575);
DISPLAY 0.617021 (-4675 3575);
PAINT SKYBLUE (-4675 3575);
FORCEPROP 1 LAST TOLERANCE 5.0%
J 0
(-4475 3675);
DISPLAY 0.617021 (-4475 3675);
PAINT SKYBLUE (-4475 3675);
FORCEPROP 1 LAST WATTAGE 1/10W
J 0
(-4500 3625);
DISPLAY 0.617021 (-4500 3625);
PAINT SKYBLUE (-4500 3625);
FORCEPROP 0 LAST ROOM NIC_SPRV
J 0
(-4625 3850);
DISPLAY 1.021277 (-4625 3850);
PAINT ORANGE (-4625 3850);
DISPLAY INVISIBLE (-4625 3850);
FORCEPROP 0 LAST BOM_COST NT_GBE_BASE
J 0
(-4625 3950);
DISPLAY 1.021277 (-4625 3950);
PAINT ORANGE (-4625 3950);
DISPLAY INVISIBLE (-4625 3950);
FORCEPROP 1 LAST PATH I122
J 0
(-4775 3875);
DISPLAY 0.978723 (-4775 3875);
PAINT WHITE (-4775 3875);
DISPLAY INVISIBLE (-4775 3875);
FORCEPROP 2 LAST CDS_LIB mstr_discrete
J 0
(-4725 3725);
PAINT MONO (-4725 3725);
DISPLAY INVISIBLE (-4725 3725);
FORCEPROP 2 LAST SEC_TYPE 0603
J 0
(-4775 3925);
DISPLAY 1.021277 (-4775 3925);
PAINT ORANGE (-4775 3925);
DISPLAY INVISIBLE (-4775 3925);
FORCEADD RES..1
(-4950 975);
FORCEPROP 1 LAST MATERIAL CHIP
J 0
(-4800 825);
DISPLAY 0.617021 (-4800 825);
PAINT SKYBLUE (-4800 825);
FORCEPROP 1 LAST PART_NUMBER G22178-002
J 0
(-5050 825);
DISPLAY 0.617021 (-5050 825);
PAINT BLUE (-5050 825);
FORCEPROP 1 LAST PACK_TYPE 0603
J 0
(-5050 875);
DISPLAY 0.617021 (-5050 875);
PAINT SKYBLUE (-5050 875);
FORCEPROP 1 LAST VALUE 0
J 2
(-5000 925);
DISPLAY 0.617021 (-5000 925);
PAINT SKYBLUE (-5000 925);
FORCEPROP 1 LASTPIN (-4850 975) $PN 2
J 0
(-4888 987);
DISPLAY 0.787234 (-4888 987);
PAINT ORANGE (-4888 987);
FORCEPROP 1 LASTPIN (-5050 975) $PN 1
J 0
(-5038 987);
DISPLAY 0.787234 (-5038 987);
PAINT ORANGE (-5038 987);
FORCEPROP 1 LAST LOCATION RT28
J 0
(-4925 900);
DISPLAY 0.617021 (-4925 900);
PAINT AQUA (-4925 900);
FORCEPROP 1 LAST TOLERANCE 5.0%
J 0
(-4825 875);
DISPLAY 0.617021 (-4825 875);
PAINT SKYBLUE (-4825 875);
FORCEPROP 1 LAST WATTAGE 1/10W
J 0
(-4625 825);
DISPLAY 0.617021 (-4625 825);
PAINT SKYBLUE (-4625 825);
FORCEPROP 2 LAST SEC_TYPE 0603
J 0
(-5000 1175);
DISPLAY 1.021277 (-5000 1175);
PAINT ORANGE (-5000 1175);
DISPLAY INVISIBLE (-5000 1175);
FORCEPROP 0 LAST SEC 1
J 0
(-5200 1075);
DISPLAY 0.680851 (-5200 1075);
PAINT MONO (-5200 1075);
DISPLAY INVISIBLE (-5200 1075);
FORCEPROP 0 LAST ROOM NIC_SPRV
J 0
(-4850 1100);
DISPLAY 1.021277 (-4850 1100);
PAINT ORANGE (-4850 1100);
DISPLAY INVISIBLE (-4850 1100);
FORCEPROP 0 LAST BOM_COST NT_GBE_BASE
J 0
(-4850 1200);
DISPLAY 1.021277 (-4850 1200);
PAINT ORANGE (-4850 1200);
DISPLAY INVISIBLE (-4850 1200);
FORCEPROP 1 LAST PATH I123
J 0
(-5000 1125);
DISPLAY 0.978723 (-5000 1125);
PAINT WHITE (-5000 1125);
DISPLAY INVISIBLE (-5000 1125);
FORCEPROP 2 LAST CDS_LIB mstr_discrete
J 0
(-4950 975);
PAINT MONO (-4950 975);
DISPLAY INVISIBLE (-4950 975);
FORCEADD RES..1
(-5325 4750);
FORCEPROP 1 LAST MATERIAL CHIP
J 0
(-5050 4650);
DISPLAY 0.638298 (-5050 4650);
PAINT SKYBLUE (-5050 4650);
FORCEPROP 1 LASTPIN (-5425 4750) $PN 1
J 0
(-5413 4762);
DISPLAY 0.617021 (-5413 4762);
PAINT WHITE (-5413 4762);
FORCEPROP 1 LASTPIN (-5225 4750) $PN 2
J 0
(-5263 4762);
DISPLAY 0.617021 (-5263 4762);
PAINT WHITE (-5263 4762);
FORCEPROP 1 LAST LOCATION R6P19
J 0
(-5425 4800);
DISPLAY 0.617021 (-5425 4800);
PAINT AQUA (-5425 4800);
FORCEPROP 1 LAST WATTAGE 1/16W
J 0
(-5050 4700);
DISPLAY 0.638298 (-5050 4700);
PAINT SKYBLUE (-5050 4700);
FORCEPROP 1 LAST TOLERANCE 5%
J 0
(-5375 4650);
DISPLAY 0.617021 (-5375 4650);
PAINT SKYBLUE (-5375 4650);
FORCEPROP 1 LAST PART_NUMBER G21497-005
J 0
(-5450 4700);
DISPLAY 0.617021 (-5450 4700);
PAINT BLUE (-5450 4700);
FORCEPROP 1 LAST PACK_TYPE 0402
J 0
(-5250 4650);
DISPLAY 0.617021 (-5250 4650);
PAINT SKYBLUE (-5250 4650);
FORCEPROP 1 LAST VALUE 0.0
J 2
(-5425 4650);
DISPLAY 0.617021 (-5425 4650);
PAINT SKYBLUE (-5425 4650);
FORCEPROP 2 LAST CDS_LOCATION R6P19
J 0
(-5800 4750);
DISPLAY 0.617021 (-5800 4750);
PAINT AQUA (-5800 4750);
DISPLAY INVISIBLE (-5800 4750);
FORCEPROP 2 LAST BOM_COST PROC_SIDEBAND
J 0
(-5325 4750);
PAINT MONO (-5325 4750);
DISPLAY INVISIBLE (-5325 4750);
FORCEPROP 2 LAST CDS_LIB mstr_discrete
J 0
(-5325 4750);
DISPLAY 1.340426 (-5325 4750);
PAINT ORANGE (-5325 4750);
DISPLAY INVISIBLE (-5325 4750);
FORCEPROP 2 LAST SEC_TYPE 0402
J 0
(-5375 4975);
DISPLAY 1.021277 (-5375 4975);
PAINT ORANGE (-5375 4975);
DISPLAY INVISIBLE (-5375 4975);
FORCEPROP 2 LAST SEC 1
J 0
(-5375 4975);
DISPLAY 0.680851 (-5375 4975);
PAINT MONO (-5375 4975);
DISPLAY INVISIBLE (-5375 4975);
FORCEPROP 2 LAST ROOM CPU0
J 0
(-5375 4900);
PAINT PEACH (-5375 4900);
DISPLAY INVISIBLE (-5375 4900);
FORCEPROP 0 LAST CDS_SEC 1
J 0
(-5025 4800);
PAINT MONO (-5025 4800);
DISPLAY INVISIBLE (-5025 4800);
FORCEPROP 1 LAST PATH I128
J 0
(-5375 4900);
DISPLAY 0.978723 (-5375 4900);
PAINT WHITE (-5375 4900);
DISPLAY INVISIBLE (-5375 4900);
FORCEADD RES..1
(-5425 2000);
FORCEPROP 1 LAST WATTAGE 1/16W
J 0
(-5225 2025);
DISPLAY 0.638298 (-5225 2025);
PAINT SKYBLUE (-5225 2025);
FORCEPROP 1 LASTPIN (-5325 2000) $PN 2
J 0
(-5363 2012);
DISPLAY 0.617021 (-5363 2012);
PAINT WHITE (-5363 2012);
FORCEPROP 1 LAST LOCATION R6P10
J 0
(-5525 2050);
DISPLAY 0.617021 (-5525 2050);
PAINT AQUA (-5525 2050);
FORCEPROP 1 LAST TOLERANCE 5%
J 0
(-5475 1900);
DISPLAY 0.617021 (-5475 1900);
PAINT SKYBLUE (-5475 1900);
FORCEPROP 1 LAST VALUE 0.0
J 2
(-5525 1900);
DISPLAY 0.617021 (-5525 1900);
PAINT SKYBLUE (-5525 1900);
FORCEPROP 1 LAST PART_NUMBER G21497-005
J 0
(-5550 1950);
DISPLAY 0.617021 (-5550 1950);
PAINT BLUE (-5550 1950);
FORCEPROP 1 LASTPIN (-5525 2000) $PN 1
J 0
(-5513 2012);
DISPLAY 0.617021 (-5513 2012);
PAINT WHITE (-5513 2012);
FORCEPROP 1 LAST PACK_TYPE 0402
J 0
(-5350 1900);
DISPLAY 0.617021 (-5350 1900);
PAINT SKYBLUE (-5350 1900);
FORCEPROP 1 LAST MATERIAL CHIP
J 0
(-5200 1900);
DISPLAY 0.638298 (-5200 1900);
PAINT SKYBLUE (-5200 1900);
FORCEPROP 1 LAST PATH I129
J 0
(-5475 2150);
DISPLAY 0.978723 (-5475 2150);
PAINT WHITE (-5475 2150);
DISPLAY INVISIBLE (-5475 2150);
FORCEPROP 2 LAST BOM_COST PROC_SIDEBAND
J 0
(-5425 2000);
PAINT MONO (-5425 2000);
DISPLAY INVISIBLE (-5425 2000);
FORCEPROP 2 LAST CDS_LIB mstr_discrete
J 0
(-5425 2000);
DISPLAY 1.340426 (-5425 2000);
PAINT ORANGE (-5425 2000);
DISPLAY INVISIBLE (-5425 2000);
FORCEPROP 2 LAST SEC_TYPE 0402
J 0
(-5475 2225);
DISPLAY 1.021277 (-5475 2225);
PAINT ORANGE (-5475 2225);
DISPLAY INVISIBLE (-5475 2225);
FORCEPROP 2 LAST SEC 1
J 0
(-5475 2225);
DISPLAY 0.680851 (-5475 2225);
PAINT MONO (-5475 2225);
DISPLAY INVISIBLE (-5475 2225);
FORCEPROP 2 LAST ROOM CPU0
J 0
(-5475 2150);
PAINT PEACH (-5475 2150);
DISPLAY INVISIBLE (-5475 2150);
FORCEPROP 0 LAST CDS_SEC 1
J 0
(-5125 2050);
PAINT MONO (-5125 2050);
DISPLAY INVISIBLE (-5125 2050);
FORCEPROP 2 LAST CDS_LOCATION R6P10
J 0
(-5900 2000);
DISPLAY 0.617021 (-5900 2000);
PAINT AQUA (-5900 2000);
DISPLAY INVISIBLE (-5900 2000);
FORCEADD IND-120NH-30-GP..1
R 1
(-1175 3675);
FORCEPROP 2 LAST TYPE IRMS=66A@DELTA_T<40C
J 0
(-1325 3425);
DISPLAY 0.638298 (-1325 3425);
PAINT GREEN (-1325 3425);
FORCEPROP 1 LAST LOCATION L4D2
J 0
(-1325 3725);
DISPLAY 0.617021 (-1325 3725);
PAINT GREEN (-1325 3725);
FORCEPROP 1 LAST VALUE IND-120NH-30-GP
J 0
(-1325 3575);
DISPLAY 0.617021 (-1325 3575);
PAINT GREEN (-1325 3575);
FORCEPROP 2 LASTPIN (-1025 3650) $PN 2
J 0
(-1015 3660);
DISPLAY 0.808511 (-1015 3660);
PAINT ORANGE (-1015 3660);
FORCEPROP 2 LASTPIN (-1325 3650) $PN 1
J 2
(-1335 3660);
DISPLAY 0.808511 (-1335 3660);
PAINT ORANGE (-1335 3660);
FORCEPROP 2 LAST ATTRIBUTE 120NH
J 0
(-1325 3525);
DISPLAY 0.638298 (-1325 3525);
PAINT GREEN (-1325 3525);
FORCEPROP 2 LAST RATED ISAT=94A@25C
J 0
(-1325 3475);
DISPLAY 0.638298 (-1325 3475);
PAINT GREEN (-1325 3475);
FORCEPROP 2 LAST PACK_SIZE DCR=0.17MOHM
J 0
(-1325 3375);
DISPLAY 0.638298 (-1325 3375);
PAINT GREEN (-1325 3375);
FORCEPROP 1 LAST PATH I130
R 1
J 0
(-1175 3675);
DISPLAY 0.617021 (-1175 3675);
PAINT GREEN (-1175 3675);
DISPLAY INVISIBLE (-1175 3675);
FORCEPROP 1 LAST PACK_TYPE DISCRET-GB2
R 1
J 0
(-1175 3675);
DISPLAY 0.617021 (-1175 3675);
PAINT GREEN (-1175 3675);
DISPLAY INVISIBLE (-1175 3675);
FORCEPROP 2 LAST SEC 1
J 0
(-1300 3750);
DISPLAY 0.680851 (-1300 3750);
PAINT MONO (-1300 3750);
DISPLAY INVISIBLE (-1300 3750);
FORCEPROP 2 LAST SEC_TYPE DISCRET-GB2
J 0
(-1300 3750);
DISPLAY 1.021277 (-1300 3750);
PAINT ORANGE (-1300 3750);
DISPLAY INVISIBLE (-1300 3750);
FORCEPROP 1 LAST CDS_LMAN_SYM_OUTLINE -75,100,75,-100
R 1
J 0
(-1175 3675);
DISPLAY 0.468085 (-1175 3675);
PAINT GREEN (-1175 3675);
DISPLAY INVISIBLE (-1175 3675);
FORCEPROP 2 LAST CDS_LIB w_hdl
R 1
J 0
(-1175 3675);
PAINT MONO (-1175 3675);
DISPLAY INVISIBLE (-1175 3675);
FORCEPROP 1 LAST PART_NUMBER 068.1202N.M001
R 1
J 0
(-1175 3675);
DISPLAY 0.617021 (-1175 3675);
PAINT GREEN (-1175 3675);
DISPLAY INVISIBLE (-1175 3675);
FORCEADD IND-120NH-30-GP..1
R 1
(-1075 950);
FORCEPROP 2 LAST PACK_SIZE DCR=0.17MOHM
J 0
(-1225 650);
DISPLAY 0.638298 (-1225 650);
PAINT GREEN (-1225 650);
FORCEPROP 2 LAST ATTRIBUTE 120NH
J 0
(-1225 800);
DISPLAY 0.638298 (-1225 800);
PAINT GREEN (-1225 800);
FORCEPROP 2 LAST RATED ISAT=94A@25C
J 0
(-1225 750);
DISPLAY 0.638298 (-1225 750);
PAINT GREEN (-1225 750);
FORCEPROP 1 LAST LOCATION L4D1
J 0
(-1225 1000);
DISPLAY 0.617021 (-1225 1000);
PAINT GREEN (-1225 1000);
FORCEPROP 2 LASTPIN (-1225 925) $PN 1
J 2
(-1235 935);
DISPLAY 0.808511 (-1235 935);
PAINT ORANGE (-1235 935);
FORCEPROP 2 LASTPIN (-925 925) $PN 2
J 0
(-915 935);
DISPLAY 0.808511 (-915 935);
PAINT ORANGE (-915 935);
FORCEPROP 2 LAST TYPE IRMS=66A@DELTA_T<40C
J 0
(-1225 700);
DISPLAY 0.638298 (-1225 700);
PAINT GREEN (-1225 700);
FORCEPROP 1 LAST VALUE IND-120NH-30-GP
J 0
(-1225 850);
DISPLAY 0.617021 (-1225 850);
PAINT GREEN (-1225 850);
FORCEPROP 1 LAST PART_NUMBER 068.1202N.M001
R 1
J 0
(-1075 950);
DISPLAY 0.617021 (-1075 950);
PAINT GREEN (-1075 950);
DISPLAY INVISIBLE (-1075 950);
FORCEPROP 2 LAST CDS_LIB w_hdl
R 1
J 0
(-1075 950);
PAINT MONO (-1075 950);
DISPLAY INVISIBLE (-1075 950);
FORCEPROP 1 LAST CDS_LMAN_SYM_OUTLINE -75,100,75,-100
R 1
J 0
(-1075 950);
DISPLAY 0.468085 (-1075 950);
PAINT GREEN (-1075 950);
DISPLAY INVISIBLE (-1075 950);
FORCEPROP 2 LAST SEC_TYPE DISCRET-GB2
J 0
(-1200 1025);
DISPLAY 1.021277 (-1200 1025);
PAINT ORANGE (-1200 1025);
DISPLAY INVISIBLE (-1200 1025);
FORCEPROP 2 LAST SEC 1
J 0
(-1200 1025);
DISPLAY 0.680851 (-1200 1025);
PAINT MONO (-1200 1025);
DISPLAY INVISIBLE (-1200 1025);
FORCEPROP 1 LAST PACK_TYPE DISCRET-GB2
R 1
J 0
(-1075 950);
DISPLAY 0.617021 (-1075 950);
PAINT GREEN (-1075 950);
DISPLAY INVISIBLE (-1075 950);
FORCEPROP 1 LAST PATH I131
R 1
J 0
(-1075 950);
DISPLAY 0.617021 (-1075 950);
PAINT GREEN (-1075 950);
DISPLAY INVISIBLE (-1075 950);
FORCEADD SC1U10V2KX-4-GP..1
(-5050 4150);
FORCEPROP 2 LAST PACK_SIZE 0402
J 0
(-4900 4050);
DISPLAY 0.638298 (-4900 4050);
PAINT GREEN (-4900 4050);
FORCEPROP 2 LASTPIN (-5050 4075) $PN 2
R 1
J 2
(-5060 4065);
DISPLAY 0.808511 (-5060 4065);
PAINT ORANGE (-5060 4065);
FORCEPROP 1 LAST VALUE SC1U10V2KX-4-GP
R 1
J 0
(-4950 3950);
DISPLAY 0.617021 (-4950 3950);
PAINT GREEN (-4950 3950);
FORCEPROP 2 LASTPIN (-5050 4225) $PN 1
R 1
J 0
(-5060 4235);
DISPLAY 0.808511 (-5060 4235);
PAINT ORANGE (-5060 4235);
FORCEPROP 1 LAST LOCATION C4D14
J 0
(-4900 4255);
DISPLAY 0.617021 (-4900 4255);
PAINT GREEN (-4900 4255);
FORCEPROP 2 LAST ATTRIBUTE 1UF
J 0
(-4900 4200);
DISPLAY 0.638298 (-4900 4200);
PAINT GREEN (-4900 4200);
FORCEPROP 2 LAST TOLERANCE 10%
J 0
(-4900 4150);
DISPLAY 0.638298 (-4900 4150);
PAINT GREEN (-4900 4150);
FORCEPROP 2 LAST RATED 10V
J 0
(-4900 4100);
DISPLAY 0.638298 (-4900 4100);
PAINT GREEN (-4900 4100);
FORCEPROP 1 LAST PACK_TYPE SMD-BCG6
J 0
(-5050 4150);
DISPLAY 0.617021 (-5050 4150);
PAINT GREEN (-5050 4150);
DISPLAY INVISIBLE (-5050 4150);
FORCEPROP 2 LAST SEC 1
J 0
(-5050 4200);
DISPLAY 0.680851 (-5050 4200);
PAINT MONO (-5050 4200);
DISPLAY INVISIBLE (-5050 4200);
FORCEPROP 2 LAST SEC_TYPE SMD-BCG6
J 0
(-5050 4200);
DISPLAY 1.021277 (-5050 4200);
PAINT ORANGE (-5050 4200);
DISPLAY INVISIBLE (-5050 4200);
FORCEPROP 1 LAST CDS_LMAN_SYM_OUTLINE -50,25,50,-25
J 0
(-5050 4150);
DISPLAY 0.468085 (-5050 4150);
PAINT GREEN (-5050 4150);
DISPLAY INVISIBLE (-5050 4150);
FORCEPROP 1 LAST PATH I132
J 0
(-5050 4150);
DISPLAY 0.617021 (-5050 4150);
PAINT GREEN (-5050 4150);
DISPLAY INVISIBLE (-5050 4150);
FORCEPROP 2 LAST CDS_LIB w_hdl
J 0
(-5050 4150);
PAINT MONO (-5050 4150);
DISPLAY INVISIBLE (-5050 4150);
FORCEPROP 1 LAST PART_NUMBER 78.10523.8FL
J 0
(-5050 4150);
DISPLAY 0.617021 (-5050 4150);
PAINT GREEN (-5050 4150);
DISPLAY INVISIBLE (-5050 4150);
FORCEADD SC1U10V2KX-4-GP..1
(-5200 1475);
FORCEPROP 2 LAST PACK_SIZE 0402
J 0
(-5050 1350);
DISPLAY 0.638298 (-5050 1350);
PAINT GREEN (-5050 1350);
FORCEPROP 2 LAST TOLERANCE 10%
J 0
(-5050 1450);
DISPLAY 0.638298 (-5050 1450);
PAINT GREEN (-5050 1450);
FORCEPROP 2 LAST RATED 10V
J 0
(-5050 1400);
DISPLAY 0.638298 (-5050 1400);
PAINT GREEN (-5050 1400);
FORCEPROP 2 LAST ATTRIBUTE 1UF
J 0
(-5050 1500);
DISPLAY 0.638298 (-5050 1500);
PAINT GREEN (-5050 1500);
FORCEPROP 1 LAST VALUE SC1U10V2KX-4-GP
R 1
J 0
(-5075 1250);
DISPLAY 0.617021 (-5075 1250);
PAINT GREEN (-5075 1250);
FORCEPROP 1 LAST LOCATION C4D6
J 0
(-5050 1555);
DISPLAY 0.617021 (-5050 1555);
PAINT GREEN (-5050 1555);
FORCEPROP 2 LASTPIN (-5200 1550) $PN 1
R 1
J 0
(-5210 1560);
DISPLAY 0.808511 (-5210 1560);
PAINT ORANGE (-5210 1560);
FORCEPROP 2 LASTPIN (-5200 1400) $PN 2
R 1
J 2
(-5210 1390);
DISPLAY 0.808511 (-5210 1390);
PAINT ORANGE (-5210 1390);
FORCEPROP 1 LAST PACK_TYPE SMD-BCG6
J 0
(-5200 1475);
DISPLAY 0.617021 (-5200 1475);
PAINT GREEN (-5200 1475);
DISPLAY INVISIBLE (-5200 1475);
FORCEPROP 2 LAST SEC 1
J 0
(-5175 1550);
DISPLAY 0.680851 (-5175 1550);
PAINT MONO (-5175 1550);
DISPLAY INVISIBLE (-5175 1550);
FORCEPROP 2 LAST SEC_TYPE SMD-BCG6
J 0
(-5175 1550);
DISPLAY 1.021277 (-5175 1550);
PAINT ORANGE (-5175 1550);
DISPLAY INVISIBLE (-5175 1550);
FORCEPROP 1 LAST PART_NUMBER 78.10523.8FL
J 0
(-5200 1475);
DISPLAY 0.617021 (-5200 1475);
PAINT GREEN (-5200 1475);
DISPLAY INVISIBLE (-5200 1475);
FORCEPROP 2 LAST CDS_LIB w_hdl
J 0
(-5200 1475);
PAINT MONO (-5200 1475);
DISPLAY INVISIBLE (-5200 1475);
FORCEPROP 1 LAST PATH I133
J 0
(-5200 1475);
DISPLAY 0.617021 (-5200 1475);
PAINT GREEN (-5200 1475);
DISPLAY INVISIBLE (-5200 1475);
FORCEPROP 1 LAST CDS_LMAN_SYM_OUTLINE -50,25,50,-25
J 0
(-5200 1475);
DISPLAY 0.468085 (-5200 1475);
PAINT GREEN (-5200 1475);
DISPLAY INVISIBLE (-5200 1475);
FORCEADD 1R3F-GP..1
(-1950 3200);
FORCEPROP 2 LAST RATED 1/10W
J 0
(-1900 3125);
DISPLAY 0.638298 (-1900 3125);
PAINT GREEN (-1900 3125);
FORCEPROP 1 LAST LOCATION RT26
J 0
(-1900 3325);
DISPLAY 0.617021 (-1900 3325);
PAINT GREEN (-1900 3325);
FORCEPROP 2 LASTPIN (-1950 3325) $PN 1
R 1
J 0
(-1960 3335);
DISPLAY 0.808511 (-1960 3335);
PAINT ORANGE (-1960 3335);
FORCEPROP 2 LAST TOLERANCE 1%
J 0
(-1900 3175);
DISPLAY 0.638298 (-1900 3175);
PAINT GREEN (-1900 3175);
FORCEPROP 0 LAST POP NOPOP
J 0
(-1900 3025);
DISPLAY 0.638298 (-1900 3025);
PAINT RED (-1900 3025);
FORCEPROP 1 LAST VALUE 1R3F-GP
J 0
(-1900 3275);
DISPLAY 0.617021 (-1900 3275);
PAINT GREEN (-1900 3275);
FORCEPROP 2 LAST ATTRIBUTE 1 OHM
J 0
(-1900 3225);
DISPLAY 0.638298 (-1900 3225);
PAINT GREEN (-1900 3225);
FORCEPROP 2 LASTPIN (-1950 3075) $PN 2
R 1
J 2
(-1960 3065);
DISPLAY 0.808511 (-1960 3065);
PAINT ORANGE (-1960 3065);
FORCEPROP 2 LAST PACK_SIZE 0603
J 0
(-1900 3075);
DISPLAY 0.638298 (-1900 3075);
PAINT GREEN (-1900 3075);
FORCEPROP 1 LAST PACK_TYPE RCL_GP
J 0
(-1950 3200);
DISPLAY 0.617021 (-1950 3200);
PAINT GREEN (-1950 3200);
DISPLAY INVISIBLE (-1950 3200);
FORCEPROP 2 LAST SEC 1
J 0
(-1900 3300);
DISPLAY 0.680851 (-1900 3300);
PAINT MONO (-1900 3300);
DISPLAY INVISIBLE (-1900 3300);
FORCEPROP 2 LAST SEC_TYPE RCL_GP
J 0
(-1900 3300);
DISPLAY 1.021277 (-1900 3300);
PAINT ORANGE (-1900 3300);
DISPLAY INVISIBLE (-1900 3300);
FORCEPROP 1 LAST PART_NUMBER 64.1R005.55L
J 0
(-1950 3200);
DISPLAY 0.617021 (-1950 3200);
PAINT GREEN (-1950 3200);
DISPLAY INVISIBLE (-1950 3200);
FORCEPROP 2 LAST CDS_LIB w_hdl
J 0
(-1950 3200);
DISPLAY INVISIBLE (-1950 3200);
FORCEPROP 1 LAST CDS_LMAN_SYM_OUTLINE -50,75,50,-75
J 0
(-1950 3200);
DISPLAY 0.468085 (-1950 3200);
PAINT GREEN (-1950 3200);
DISPLAY INVISIBLE (-1950 3200);
FORCEPROP 1 LAST PATH I134
J 0
(-1950 3200);
DISPLAY 0.617021 (-1950 3200);
PAINT GREEN (-1950 3200);
DISPLAY INVISIBLE (-1950 3200);
FORCEADD 1R3F-GP..1
(-1975 550);
FORCEPROP 2 LAST PACK_SIZE 0603
J 0
(-1775 450);
DISPLAY 0.638298 (-1775 450);
PAINT GREEN (-1775 450);
FORCEPROP 1 LAST VALUE 1R3F-GP
J 0
(-1925 600);
DISPLAY 0.617021 (-1925 600);
PAINT GREEN (-1925 600);
FORCEPROP 2 LAST ATTRIBUTE 1 OHM
J 0
(-1925 550);
DISPLAY 0.638298 (-1925 550);
PAINT GREEN (-1925 550);
FORCEPROP 2 LAST TOLERANCE 1%
J 0
(-1925 500);
DISPLAY 0.638298 (-1925 500);
PAINT GREEN (-1925 500);
FORCEPROP 0 LAST POP NOPOP
J 0
(-1925 400);
DISPLAY 0.638298 (-1925 400);
PAINT RED (-1925 400);
FORCEPROP 2 LAST RATED 1/10W
J 0
(-1925 450);
DISPLAY 0.638298 (-1925 450);
PAINT GREEN (-1925 450);
FORCEPROP 1 LAST LOCATION RT27
J 0
(-1925 650);
DISPLAY 0.617021 (-1925 650);
PAINT GREEN (-1925 650);
FORCEPROP 2 LASTPIN (-1975 675) $PN 1
R 1
J 0
(-1985 685);
DISPLAY 0.808511 (-1985 685);
PAINT ORANGE (-1985 685);
FORCEPROP 2 LASTPIN (-1975 425) $PN 2
R 1
J 2
(-1985 415);
DISPLAY 0.808511 (-1985 415);
PAINT ORANGE (-1985 415);
FORCEPROP 1 LAST CDS_LMAN_SYM_OUTLINE -50,75,50,-75
J 0
(-1975 550);
DISPLAY 0.468085 (-1975 550);
PAINT GREEN (-1975 550);
DISPLAY INVISIBLE (-1975 550);
FORCEPROP 2 LAST CDS_LIB w_hdl
J 0
(-1975 550);
DISPLAY INVISIBLE (-1975 550);
FORCEPROP 1 LAST PART_NUMBER 64.1R005.55L
J 0
(-1975 550);
DISPLAY 0.617021 (-1975 550);
PAINT GREEN (-1975 550);
DISPLAY INVISIBLE (-1975 550);
FORCEPROP 2 LAST SEC_TYPE RCL_GP
J 0
(-1925 650);
DISPLAY 1.021277 (-1925 650);
PAINT ORANGE (-1925 650);
DISPLAY INVISIBLE (-1925 650);
FORCEPROP 2 LAST SEC 1
J 0
(-1925 650);
DISPLAY 0.680851 (-1925 650);
PAINT MONO (-1925 650);
DISPLAY INVISIBLE (-1925 650);
FORCEPROP 1 LAST PACK_TYPE RCL_GP
J 0
(-1975 550);
DISPLAY 0.617021 (-1975 550);
PAINT GREEN (-1975 550);
DISPLAY INVISIBLE (-1975 550);
FORCEPROP 1 LAST PATH I135
J 0
(-1975 550);
DISPLAY 0.617021 (-1975 550);
PAINT GREEN (-1975 550);
DISPLAY INVISIBLE (-1975 550);
FORCEADD GND..1
(-500 3100);
FORCEPROP 3 LASTPIN (-500 3150) SIG_NAME GND\g
J 0
(-490 3160);
DISPLAY 0.659574 (-490 3160);
PAINT MONO (-490 3160);
DISPLAY INVISIBLE (-490 3160);
FORCEPROP 2 LAST ROOM PVCCIN_CPU0_PWR_VR
J 0
(-1050 3175);
DISPLAY 1.936170 (-1050 3175);
PAINT ORANGE (-1050 3175);
DISPLAY INVISIBLE (-1050 3175);
FORCEPROP 2 LAST BOM_COST PROC_VRD_VCCIN_CPU0
J 0
(-875 3175);
DISPLAY 1.446809 (-875 3175);
PAINT MONO (-875 3175);
DISPLAY INVISIBLE (-875 3175);
FORCEPROP 2 LAST CDS_LIB mstr_symbols
J 0
(-500 3100);
DISPLAY 1.936170 (-500 3100);
PAINT ORANGE (-500 3100);
DISPLAY INVISIBLE (-500 3100);
FORCEPROP 1 LAST VOLTAGE 0
J 0
(-500 3100);
PAINT SKYBLUE (-500 3100);
DISPLAY INVISIBLE (-500 3100);
FORCEPROP 1 LAST SIZE 1B
J 0
(-425 3050);
DISPLAY 1.723404 (-425 3050);
PAINT GREEN (-425 3050);
DISPLAY INVISIBLE (-425 3050);
FORCEPROP 1 LAST PATH I14
J 0
(-425 3100);
DISPLAY 0.872340 (-425 3100);
PAINT AQUA (-425 3100);
DISPLAY INVISIBLE (-425 3100);
FORCEPROP 1 LAST BODY_TYPE PLUMBING
J 0
(-545 3057);
DISPLAY 0.340426 (-545 3057);
PAINT GREEN (-545 3057);
DISPLAY INVISIBLE (-545 3057);
FORCEPROP 1 LAST HDL_POWER GND
J 0
(-500 3250);
DISPLAY 1.723404 (-500 3250);
PAINT GREEN (-500 3250);
DISPLAY INVISIBLE (-500 3250);
FORCEADD CAPP..1
(-925 2600);
FORCEPROP 1 LAST LOCATION C6R3
J 0
(-875 2700);
DISPLAY 0.617021 (-875 2700);
PAINT AQUA (-875 2700);
FORCEPROP 1 LASTPIN (-925 2700) $PN 1
J 0
(-915 2685);
DISPLAY 0.617021 (-915 2685);
PAINT GREEN (-915 2685);
FORCEPROP 1 LAST PART_NUMBER 699013-049
J 0
(-875 2400);
DISPLAY 0.617021 (-875 2400);
PAINT BLUE (-875 2400);
FORCEPROP 1 LAST PACK_TYPE 3018
J 0
(-875 2450);
DISPLAY 0.617021 (-875 2450);
PAINT SKYBLUE (-875 2450);
FORCEPROP 1 LAST MATERIAL ALUM
J 0
(-875 2500);
DISPLAY 0.617021 (-875 2500);
PAINT SKYBLUE (-875 2500);
FORCEPROP 1 LAST VALUE 470UF
J 0
(-875 2650);
DISPLAY 0.617021 (-875 2650);
PAINT SKYBLUE (-875 2650);
FORCEPROP 1 LAST TOLERANCE 20%
J 0
(-875 2600);
DISPLAY 0.617021 (-875 2600);
PAINT SKYBLUE (-875 2600);
FORCEPROP 1 LASTPIN (-925 2500) $PN 2
J 0
(-915 2485);
DISPLAY 0.617021 (-915 2485);
PAINT GREEN (-915 2485);
FORCEPROP 1 LAST VOLTAGE 2.5V
J 0
(-875 2550);
DISPLAY 0.638298 (-875 2550);
PAINT SKYBLUE (-875 2550);
FORCEPROP 0 LAST GROUP PWR_BULK_CAP
J 0
(-875 2350);
DISPLAY 0.638298 (-875 2350);
PAINT BROWN (-875 2350);
DISPLAY BOTH (-875 2350);
FORCEPROP 2 LAST SEC_TYPE 3018
J 0
(-860 2810);
DISPLAY 1.021277 (-860 2810);
PAINT ORANGE (-860 2810);
DISPLAY INVISIBLE (-860 2810);
FORCEPROP 2 LAST SEC 1
J 0
(-875 2800);
PAINT MONO (-875 2800);
DISPLAY INVISIBLE (-875 2800);
FORCEPROP 2 LAST ROOM PVCCIN_CPU0_DECAP_VR
J 0
(-875 2725);
PAINT MONO (-875 2725);
DISPLAY INVISIBLE (-875 2725);
FORCEPROP 1 LAST PATH I16
J 0
(-875 2750);
DISPLAY 0.978723 (-875 2750);
PAINT ORANGE (-875 2750);
DISPLAY INVISIBLE (-875 2750);
FORCEPROP 2 LAST BOM_COST PROC_VRD_VCCIN_CPU0
J 0
(-875 2750);
PAINT MONO (-875 2750);
DISPLAY INVISIBLE (-875 2750);
FORCEPROP 2 LAST CDS_LOCATION C6R3
J 0
(-875 2700);
DISPLAY 0.617021 (-875 2700);
PAINT AQUA (-875 2700);
DISPLAY INVISIBLE (-875 2700);
FORCEPROP 2 LAST CDS_LIB mstr_discrete
J 0
(-925 2600);
PAINT MONO (-925 2600);
DISPLAY INVISIBLE (-925 2600);
FORCEADD GND..1
(-475 2225);
FORCEPROP 3 LASTPIN (-475 2275) SIG_NAME GND\g
J 0
(-465 2285);
DISPLAY 0.659574 (-465 2285);
PAINT MONO (-465 2285);
DISPLAY INVISIBLE (-465 2285);
FORCEPROP 1 LAST HDL_POWER GND
J 0
(-475 2375);
DISPLAY 0.893617 (-475 2375);
PAINT GREEN (-475 2375);
DISPLAY INVISIBLE (-475 2375);
FORCEPROP 1 LAST BODY_TYPE PLUMBING
J 0
(-520 2182);
DISPLAY 0.340426 (-520 2182);
PAINT GREEN (-520 2182);
DISPLAY INVISIBLE (-520 2182);
FORCEPROP 1 LAST VOLTAGE 0
J 0
(-475 2225);
PAINT SKYBLUE (-475 2225);
DISPLAY INVISIBLE (-475 2225);
FORCEPROP 2 LAST CDS_LIB mstr_symbols
J 1
(-475 2225);
PAINT ORANGE (-475 2225);
DISPLAY INVISIBLE (-475 2225);
FORCEPROP 1 LAST SIZE 1B
J 0
(-400 2175);
DISPLAY 0.893617 (-400 2175);
PAINT GREEN (-400 2175);
DISPLAY INVISIBLE (-400 2175);
FORCEPROP 1 LAST PATH I17
J 0
(-400 2225);
DISPLAY 0.872340 (-400 2225);
PAINT AQUA (-400 2225);
DISPLAY INVISIBLE (-400 2225);
FORCEPROP 2 LAST BOM_COST PROC_VRD_VCCIN_CPU0
J 0
(-850 2300);
PAINT MONO (-850 2300);
DISPLAY INVISIBLE (-850 2300);
FORCEPROP 2 LAST ROOM PVCCIN_CPU0_DECAP_VR
J 0
(-1025 2300);
PAINT ORANGE (-1025 2300);
DISPLAY INVISIBLE (-1025 2300);
FORCEADD CAPP..1
(-1400 2600);
FORCEPROP 1 LAST PACK_TYPE 3018
J 0
(-1350 2450);
DISPLAY 0.617021 (-1350 2450);
PAINT SKYBLUE (-1350 2450);
FORCEPROP 1 LASTPIN (-1400 2500) $PN 2
J 0
(-1390 2485);
DISPLAY 0.617021 (-1390 2485);
PAINT GREEN (-1390 2485);
FORCEPROP 1 LASTPIN (-1400 2700) $PN 1
J 0
(-1390 2685);
DISPLAY 0.617021 (-1390 2685);
PAINT GREEN (-1390 2685);
FORCEPROP 1 LAST LOCATION C6R9
J 0
(-1350 2700);
DISPLAY 0.617021 (-1350 2700);
PAINT AQUA (-1350 2700);
FORCEPROP 1 LAST TOLERANCE 20%
J 0
(-1350 2600);
DISPLAY 0.617021 (-1350 2600);
PAINT SKYBLUE (-1350 2600);
FORCEPROP 1 LAST PART_NUMBER 699013-049
J 0
(-1350 2400);
DISPLAY 0.617021 (-1350 2400);
PAINT BLUE (-1350 2400);
FORCEPROP 1 LAST MATERIAL ALUM
J 0
(-1350 2500);
DISPLAY 0.617021 (-1350 2500);
PAINT SKYBLUE (-1350 2500);
FORCEPROP 1 LAST VOLTAGE 2.5V
J 0
(-1350 2550);
DISPLAY 0.638298 (-1350 2550);
PAINT SKYBLUE (-1350 2550);
FORCEPROP 1 LAST VALUE 470UF
J 0
(-1350 2650);
DISPLAY 0.617021 (-1350 2650);
PAINT SKYBLUE (-1350 2650);
FORCEPROP 0 LAST GROUP PWR_BULK_CAP
J 0
(-1350 2300);
DISPLAY 0.638298 (-1350 2300);
PAINT BROWN (-1350 2300);
DISPLAY BOTH (-1350 2300);
FORCEPROP 2 LAST SEC_TYPE 3018
J 0
(-1335 2810);
DISPLAY 1.021277 (-1335 2810);
PAINT ORANGE (-1335 2810);
DISPLAY INVISIBLE (-1335 2810);
FORCEPROP 2 LAST SEC 1
J 0
(-1350 2800);
PAINT MONO (-1350 2800);
DISPLAY INVISIBLE (-1350 2800);
FORCEPROP 2 LAST BOM_COST PROC_VRD_VCCIN_CPU0
J 0
(-1350 2750);
PAINT MONO (-1350 2750);
DISPLAY INVISIBLE (-1350 2750);
FORCEPROP 1 LAST PATH I18
J 0
(-1350 2750);
DISPLAY 0.978723 (-1350 2750);
PAINT ORANGE (-1350 2750);
DISPLAY INVISIBLE (-1350 2750);
FORCEPROP 2 LAST ROOM PVCCIN_CPU0_DECAP_VR
J 0
(-1350 2725);
PAINT MONO (-1350 2725);
DISPLAY INVISIBLE (-1350 2725);
FORCEPROP 2 LAST CDS_LOCATION C6R9
J 0
(-1350 2700);
DISPLAY 0.617021 (-1350 2700);
PAINT AQUA (-1350 2700);
DISPLAY INVISIBLE (-1350 2700);
FORCEPROP 2 LAST CDS_LIB mstr_discrete
J 0
(-1400 2600);
PAINT MONO (-1400 2600);
DISPLAY INVISIBLE (-1400 2600);
FORCEADD OFFPAGE..2
(-975 2075);
FORCEPROP 2 LAST $XR0 201 
J 0
(-786 2075);
DISPLAY 0.638298 (-786 2075);
PAINT MONO (-786 2075);
FORCEPROP 1 LAST COMMENT_BODY TRUE
J 0
(-1020 1980);
DISPLAY 1.723404 (-1020 1980);
PAINT GREEN (-1020 1980);
DISPLAY INVISIBLE (-1020 1980);
FORCEPROP 1 LAST OFFPAGE TRUE
J 0
(-650 1950);
DISPLAY 1.723404 (-650 1950);
PAINT GREEN (-650 1950);
DISPLAY INVISIBLE (-650 1950);
FORCEPROP 2 LAST BOM_COST PROC_VRD_VCCIN_CPU0
J 0
(-775 2125);
DISPLAY 1.446809 (-775 2125);
PAINT MONO (-775 2125);
DISPLAY INVISIBLE (-775 2125);
FORCEPROP 2 LAST CDS_LIB mstr_standard
J 0
(-975 2075);
PAINT ORANGE (-975 2075);
DISPLAY INVISIBLE (-975 2075);
FORCEPROP 2 LAST PATH I19
J 0
(-800 2150);
DISPLAY 1.021277 (-800 2150);
PAINT ORANGE (-800 2150);
DISPLAY INVISIBLE (-800 2150);
FORCEPROP 2 LAST ROOM PVCCIN_CPU0_PWR_VR
J 0
(-1375 2150);
DISPLAY 1.936170 (-1375 2150);
PAINT ORANGE (-1375 2150);
DISPLAY INVISIBLE (-1375 2150);
FORCEADD CAP..1
(-6700 4175);
FORCEPROP 1 LAST PART_NUMBER C95333-007
J 0
(-6650 4025);
DISPLAY 0.617021 (-6650 4025);
PAINT BLUE (-6650 4025);
FORCEPROP 1 LAST MATERIAL X6S
J 0
(-6650 4075);
DISPLAY 0.617021 (-6650 4075);
PAINT SKYBLUE (-6650 4075);
FORCEPROP 1 LAST TOLERANCE 10%
J 0
(-6650 4125);
DISPLAY 0.617021 (-6650 4125);
PAINT SKYBLUE (-6650 4125);
FORCEPROP 1 LAST VOLTAGE 16V
J 0
(-6650 4175);
DISPLAY 0.617021 (-6650 4175);
PAINT SKYBLUE (-6650 4175);
FORCEPROP 1 LASTPIN (-6700 4275) $PN 1
J 0
(-6690 4255);
DISPLAY 0.617021 (-6690 4255);
PAINT ORANGE (-6690 4255);
FORCEPROP 1 LAST VALUE 10UF
J 0
(-6650 4225);
DISPLAY 0.617021 (-6650 4225);
PAINT SKYBLUE (-6650 4225);
FORCEPROP 1 LAST LOCATION C6R6
J 0
(-6650 4275);
DISPLAY 0.617021 (-6650 4275);
PAINT AQUA (-6650 4275);
FORCEPROP 1 LASTPIN (-6700 4075) $PN 2
J 0
(-6690 4055);
DISPLAY 0.617021 (-6690 4055);
PAINT ORANGE (-6690 4055);
FORCEPROP 1 LAST PACK_TYPE 0805
J 0
(-6650 3975);
DISPLAY 0.617021 (-6650 3975);
PAINT SKYBLUE (-6650 3975);
FORCEPROP 2 LAST ROOM PVCCIN_CPU0_PWR_VR
J 0
(-6650 4325);
DISPLAY 1.361702 (-6650 4325);
PAINT ORANGE (-6650 4325);
DISPLAY INVISIBLE (-6650 4325);
FORCEPROP 2 LAST SEC 1
J 0
(-6650 4375);
DISPLAY 0.680851 (-6650 4375);
PAINT MONO (-6650 4375);
DISPLAY INVISIBLE (-6650 4375);
FORCEPROP 2 LAST SEC_TYPE 0805
J 0
(-6650 4375);
DISPLAY 1.021277 (-6650 4375);
PAINT ORANGE (-6650 4375);
DISPLAY INVISIBLE (-6650 4375);
FORCEPROP 2 LAST CDS_LIB mstr_discrete
J 0
(-6700 4175);
PAINT ORANGE (-6700 4175);
DISPLAY INVISIBLE (-6700 4175);
FORCEPROP 2 LAST CDS_LOCATION C6R6
J 0
(-6650 4275);
DISPLAY 0.617021 (-6650 4275);
PAINT AQUA (-6650 4275);
DISPLAY INVISIBLE (-6650 4275);
FORCEPROP 1 LAST PATH I2
J 0
(-6650 4325);
DISPLAY 0.978723 (-6650 4325);
PAINT WHITE (-6650 4325);
DISPLAY INVISIBLE (-6650 4325);
FORCEADD OFFPAGE..2
(-1175 1425);
FORCEPROP 2 LAST $XR3 201 
J 0
(-626 1425);
DISPLAY 0.638298 (-626 1425);
PAINT MONO (-626 1425);
FORCEPROP 2 LAST $XR2 204 
J 0
(-746 1425);
DISPLAY 0.638298 (-746 1425);
PAINT MONO (-746 1425);
FORCEPROP 2 LAST $XR1 203 
J 0
(-866 1425);
DISPLAY 0.638298 (-866 1425);
PAINT MONO (-866 1425);
FORCEPROP 2 LAST $XR0 202 
J 0
(-986 1425);
DISPLAY 0.638298 (-986 1425);
PAINT MONO (-986 1425);
FORCEPROP 1 LAST COMMENT_BODY TRUE
J 0
(-1220 1330);
DISPLAY 1.723404 (-1220 1330);
PAINT GREEN (-1220 1330);
DISPLAY INVISIBLE (-1220 1330);
FORCEPROP 1 LAST OFFPAGE TRUE
J 0
(-850 1300);
DISPLAY 1.723404 (-850 1300);
PAINT GREEN (-850 1300);
DISPLAY INVISIBLE (-850 1300);
FORCEPROP 2 LAST ROOM PVCCIN_CPU0_PWR_VR
J 0
(-1575 1500);
DISPLAY 1.936170 (-1575 1500);
PAINT ORANGE (-1575 1500);
DISPLAY INVISIBLE (-1575 1500);
FORCEPROP 2 LAST CDS_LIB mstr_standard
J 0
(-1175 1425);
PAINT ORANGE (-1175 1425);
DISPLAY INVISIBLE (-1175 1425);
FORCEPROP 2 LAST BOM_COST PROC_VRD_VCCIN_CPU0
J 0
(-975 1475);
DISPLAY 1.446809 (-975 1475);
PAINT MONO (-975 1475);
DISPLAY INVISIBLE (-975 1475);
FORCEPROP 2 LAST PATH I20
J 0
(-1000 1500);
DISPLAY 1.021277 (-1000 1500);
PAINT ORANGE (-1000 1500);
DISPLAY INVISIBLE (-1000 1500);
FORCEADD OFFPAGE..2
(-900 1750);
FORCEPROP 2 LAST $XR0 201 
J 0
(-711 1750);
DISPLAY 0.638298 (-711 1750);
PAINT MONO (-711 1750);
FORCEPROP 1 LAST COMMENT_BODY TRUE
J 0
(-945 1655);
DISPLAY 1.723404 (-945 1655);
PAINT GREEN (-945 1655);
DISPLAY INVISIBLE (-945 1655);
FORCEPROP 1 LAST OFFPAGE TRUE
J 0
(-575 1625);
DISPLAY 1.723404 (-575 1625);
PAINT GREEN (-575 1625);
DISPLAY INVISIBLE (-575 1625);
FORCEPROP 2 LAST BOM_COST PROC_VRD_VCCIN_CPU0
J 0
(-700 1800);
DISPLAY 1.446809 (-700 1800);
PAINT MONO (-700 1800);
DISPLAY INVISIBLE (-700 1800);
FORCEPROP 2 LAST PATH I21
J 0
(-725 1825);
DISPLAY 1.021277 (-725 1825);
PAINT ORANGE (-725 1825);
DISPLAY INVISIBLE (-725 1825);
FORCEPROP 2 LAST ROOM PVCCIN_CPU0_PWR_VR
J 0
(-1300 1825);
DISPLAY 1.936170 (-1300 1825);
PAINT ORANGE (-1300 1825);
DISPLAY INVISIBLE (-1300 1825);
FORCEPROP 2 LAST CDS_LIB mstr_standard
J 0
(-900 1750);
PAINT ORANGE (-900 1750);
DISPLAY INVISIBLE (-900 1750);
FORCEADD CAP_A..1
(-700 725);
FORCEPROP 1 LASTPIN (-700 625) $PN 2
J 0
(-690 605);
DISPLAY 0.617021 (-690 605);
PAINT ORANGE (-690 605);
FORCEPROP 1 LAST MATERIAL X6S
J 0
(-650 675);
DISPLAY 0.617021 (-650 675);
PAINT SKYBLUE (-650 675);
FORCEPROP 1 LAST VALUE 22.0UF
J 0
(-650 825);
DISPLAY 0.617021 (-650 825);
PAINT SKYBLUE (-650 825);
FORCEPROP 1 LAST LOCATION C6P3
J 0
(-650 875);
DISPLAY 0.617021 (-650 875);
PAINT AQUA (-650 875);
FORCEPROP 1 LASTPIN (-700 825) $PN 1
J 0
(-690 805);
DISPLAY 0.617021 (-690 805);
PAINT ORANGE (-690 805);
FORCEPROP 1 LAST VOLTAGE 4V
J 0
(-650 775);
DISPLAY 0.617021 (-650 775);
PAINT SKYBLUE (-650 775);
FORCEPROP 1 LAST TOLERANCE 20%
J 0
(-650 725);
DISPLAY 0.617021 (-650 725);
PAINT SKYBLUE (-650 725);
FORCEPROP 1 LAST PART_NUMBER E15431-004
J 0
(-650 625);
DISPLAY 0.617021 (-650 625);
PAINT BLUE (-650 625);
FORCEPROP 1 LAST PACK_TYPE 0603V
J 0
(-650 575);
DISPLAY 0.617021 (-650 575);
PAINT SKYBLUE (-650 575);
FORCEPROP 0 LAST GROUP PWR_MLCC_CAP
J 0
(-650 525);
DISPLAY 0.638298 (-650 525);
PAINT BROWN (-650 525);
DISPLAY BOTH (-650 525);
FORCEPROP 2 LAST CDS_LIB dev_discrete
J 0
(-700 725);
PAINT ORANGE (-700 725);
DISPLAY INVISIBLE (-700 725);
FORCEPROP 2 LAST ROOM PVCCIN_CPU0_PWR_VR
J 0
(-650 875);
DISPLAY 1.446809 (-650 875);
PAINT MONO (-650 875);
DISPLAY INVISIBLE (-650 875);
FORCEPROP 1 LAST PATH I25
J 0
(-650 875);
DISPLAY 0.978723 (-650 875);
PAINT WHITE (-650 875);
DISPLAY INVISIBLE (-650 875);
FORCEPROP 2 LAST SEC 1
J 0
(-645 925);
DISPLAY 0.680851 (-645 925);
PAINT MONO (-645 925);
DISPLAY INVISIBLE (-645 925);
FORCEPROP 2 LAST SEC_TYPE 0603V
J 0
(-645 925);
DISPLAY 1.021277 (-645 925);
PAINT ORANGE (-645 925);
DISPLAY INVISIBLE (-645 925);
FORCEPROP 2 LAST CDS_SEC 1
J 0
(-650 875);
PAINT ORANGE (-650 875);
DISPLAY INVISIBLE (-650 875);
FORCEPROP 2 LAST BOM_COST PROC_VRD_VCCIN_CPU0
J 0
(-650 875);
DISPLAY 1.446809 (-650 875);
PAINT MONO (-650 875);
DISPLAY INVISIBLE (-650 875);
FORCEPROP 2 LAST CDS_LOCATION C6P3
J 0
(-650 825);
DISPLAY 0.617021 (-650 825);
PAINT AQUA (-650 825);
DISPLAY INVISIBLE (-650 825);
FORCEADD GND..1
(-700 425);
FORCEPROP 3 LASTPIN (-700 475) SIG_NAME GND\g
J 0
(-690 485);
DISPLAY 0.659574 (-690 485);
PAINT MONO (-690 485);
DISPLAY INVISIBLE (-690 485);
FORCEPROP 1 LAST HDL_POWER GND
J 0
(-700 575);
DISPLAY 1.723404 (-700 575);
PAINT GREEN (-700 575);
DISPLAY INVISIBLE (-700 575);
FORCEPROP 1 LAST BODY_TYPE PLUMBING
J 0
(-745 382);
DISPLAY 0.340426 (-745 382);
PAINT GREEN (-745 382);
DISPLAY INVISIBLE (-745 382);
FORCEPROP 1 LAST SIZE 1B
J 0
(-625 375);
DISPLAY 1.723404 (-625 375);
PAINT GREEN (-625 375);
DISPLAY INVISIBLE (-625 375);
FORCEPROP 1 LAST PATH I26
J 0
(-625 425);
DISPLAY 0.872340 (-625 425);
PAINT AQUA (-625 425);
DISPLAY INVISIBLE (-625 425);
FORCEPROP 1 LAST VOLTAGE 0
J 0
(-700 425);
PAINT SKYBLUE (-700 425);
DISPLAY INVISIBLE (-700 425);
FORCEPROP 2 LAST CDS_LIB mstr_symbols
J 0
(-700 425);
PAINT ORANGE (-700 425);
DISPLAY INVISIBLE (-700 425);
FORCEPROP 2 LAST BOM_COST PROC_VRD_VCCIN_CPU0
J 0
(-1075 500);
DISPLAY 1.446809 (-1075 500);
PAINT MONO (-1075 500);
DISPLAY INVISIBLE (-1075 500);
FORCEPROP 2 LAST ROOM PVCCIN_CPU0_PWR_VR
J 0
(-1250 500);
DISPLAY 1.936170 (-1250 500);
PAINT ORANGE (-1250 500);
DISPLAY INVISIBLE (-1250 500);
FORCEADD GND..1
(-2475 3275);
FORCEPROP 3 LASTPIN (-2475 3325) SIG_NAME GND\g
J 0
(-2465 3335);
DISPLAY 0.659574 (-2465 3335);
PAINT MONO (-2465 3335);
DISPLAY INVISIBLE (-2465 3335);
FORCEPROP 1 LAST HDL_POWER GND
J 0
(-2475 3425);
DISPLAY 1.723404 (-2475 3425);
PAINT GREEN (-2475 3425);
DISPLAY INVISIBLE (-2475 3425);
FORCEPROP 1 LAST BODY_TYPE PLUMBING
J 0
(-2520 3232);
DISPLAY 0.340426 (-2520 3232);
PAINT GREEN (-2520 3232);
DISPLAY INVISIBLE (-2520 3232);
FORCEPROP 2 LAST CDS_LIB mstr_symbols
J 0
(-2475 3275);
DISPLAY 1.936170 (-2475 3275);
PAINT ORANGE (-2475 3275);
DISPLAY INVISIBLE (-2475 3275);
FORCEPROP 1 LAST SIZE 1B
J 0
(-2400 3225);
DISPLAY 1.723404 (-2400 3225);
PAINT GREEN (-2400 3225);
DISPLAY INVISIBLE (-2400 3225);
FORCEPROP 1 LAST VOLTAGE 0
J 0
(-2475 3275);
PAINT SKYBLUE (-2475 3275);
DISPLAY INVISIBLE (-2475 3275);
FORCEPROP 1 LAST PATH I27
J 0
(-2400 3275);
DISPLAY 0.872340 (-2400 3275);
PAINT AQUA (-2400 3275);
DISPLAY INVISIBLE (-2400 3275);
FORCEPROP 2 LAST BOM_COST PROC_VRD_VCCIN_CPU0
J 0
(-2850 3350);
DISPLAY 1.446809 (-2850 3350);
PAINT MONO (-2850 3350);
DISPLAY INVISIBLE (-2850 3350);
FORCEPROP 2 LAST ROOM PVCCIN_CPU0_PWR_VR
J 0
(-3025 3350);
DISPLAY 1.936170 (-3025 3350);
PAINT ORANGE (-3025 3350);
DISPLAY INVISIBLE (-3025 3350);
FORCEADD CAPP..1
(-1850 2600);
FORCEPROP 1 LAST MATERIAL ALUM
J 0
(-1800 2500);
DISPLAY 0.617021 (-1800 2500);
PAINT SKYBLUE (-1800 2500);
FORCEPROP 1 LAST VOLTAGE 2.5V
J 0
(-1800 2550);
DISPLAY 0.638298 (-1800 2550);
PAINT SKYBLUE (-1800 2550);
FORCEPROP 1 LAST LOCATION C6P23
J 0
(-1800 2700);
DISPLAY 0.617021 (-1800 2700);
PAINT AQUA (-1800 2700);
FORCEPROP 1 LAST VALUE 470UF
J 0
(-1800 2650);
DISPLAY 0.617021 (-1800 2650);
PAINT SKYBLUE (-1800 2650);
FORCEPROP 1 LAST PACK_TYPE 3018
J 0
(-1800 2450);
DISPLAY 0.617021 (-1800 2450);
PAINT SKYBLUE (-1800 2450);
FORCEPROP 1 LASTPIN (-1850 2500) $PN 2
J 0
(-1840 2485);
DISPLAY 0.617021 (-1840 2485);
PAINT GREEN (-1840 2485);
FORCEPROP 1 LASTPIN (-1850 2700) $PN 1
J 0
(-1840 2685);
DISPLAY 0.617021 (-1840 2685);
PAINT GREEN (-1840 2685);
FORCEPROP 1 LAST TOLERANCE 20%
J 0
(-1800 2600);
DISPLAY 0.617021 (-1800 2600);
PAINT SKYBLUE (-1800 2600);
FORCEPROP 1 LAST PART_NUMBER 699013-049
J 0
(-1800 2400);
DISPLAY 0.617021 (-1800 2400);
PAINT BLUE (-1800 2400);
FORCEPROP 0 LAST GROUP PWR_BULK_CAP
J 0
(-1800 2350);
DISPLAY 0.638298 (-1800 2350);
PAINT BROWN (-1800 2350);
DISPLAY BOTH (-1800 2350);
FORCEPROP 2 LAST SEC_TYPE 3018
J 0
(-1785 2810);
DISPLAY 1.021277 (-1785 2810);
PAINT ORANGE (-1785 2810);
DISPLAY INVISIBLE (-1785 2810);
FORCEPROP 2 LAST BOM_COST PROC_VRD_VCCIN_CPU0
J 0
(-1800 2750);
PAINT MONO (-1800 2750);
DISPLAY INVISIBLE (-1800 2750);
FORCEPROP 2 LAST SEC 1
J 0
(-1800 2800);
PAINT MONO (-1800 2800);
DISPLAY INVISIBLE (-1800 2800);
FORCEPROP 2 LAST CDS_LOCATION C6P23
J 0
(-1800 2700);
DISPLAY 0.617021 (-1800 2700);
PAINT AQUA (-1800 2700);
DISPLAY INVISIBLE (-1800 2700);
FORCEPROP 1 LAST PATH I28
J 0
(-1800 2750);
DISPLAY 0.978723 (-1800 2750);
PAINT ORANGE (-1800 2750);
DISPLAY INVISIBLE (-1800 2750);
FORCEPROP 2 LAST ROOM PVCCIN_CPU0_DECAP_VR
J 0
(-1800 2725);
PAINT MONO (-1800 2725);
DISPLAY INVISIBLE (-1800 2725);
FORCEPROP 2 LAST CDS_LIB mstr_discrete
J 0
(-1850 2600);
PAINT MONO (-1850 2600);
DISPLAY INVISIBLE (-1850 2600);
FORCEADD CAPP..1
(-2300 2600);
FORCEPROP 1 LAST LOCATION C6P14
J 0
(-2250 2700);
DISPLAY 0.617021 (-2250 2700);
PAINT AQUA (-2250 2700);
FORCEPROP 1 LAST VALUE 470UF
J 0
(-2250 2650);
DISPLAY 0.617021 (-2250 2650);
PAINT SKYBLUE (-2250 2650);
FORCEPROP 1 LAST PACK_TYPE 3018
J 0
(-2250 2450);
DISPLAY 0.617021 (-2250 2450);
PAINT SKYBLUE (-2250 2450);
FORCEPROP 1 LAST MATERIAL ALUM
J 0
(-2250 2500);
DISPLAY 0.617021 (-2250 2500);
PAINT SKYBLUE (-2250 2500);
FORCEPROP 1 LAST TOLERANCE 20%
J 0
(-2250 2600);
DISPLAY 0.617021 (-2250 2600);
PAINT SKYBLUE (-2250 2600);
FORCEPROP 1 LASTPIN (-2300 2700) $PN 1
J 0
(-2290 2685);
DISPLAY 0.617021 (-2290 2685);
PAINT GREEN (-2290 2685);
FORCEPROP 1 LASTPIN (-2300 2500) $PN 2
J 0
(-2290 2485);
DISPLAY 0.617021 (-2290 2485);
PAINT GREEN (-2290 2485);
FORCEPROP 1 LAST VOLTAGE 2.5V
J 0
(-2250 2550);
DISPLAY 0.638298 (-2250 2550);
PAINT SKYBLUE (-2250 2550);
FORCEPROP 1 LAST PART_NUMBER 699013-049
J 0
(-2250 2400);
DISPLAY 0.617021 (-2250 2400);
PAINT BLUE (-2250 2400);
FORCEPROP 0 LAST GROUP PWR_BULK_CAP
J 0
(-2250 2300);
DISPLAY 0.638298 (-2250 2300);
PAINT BROWN (-2250 2300);
DISPLAY BOTH (-2250 2300);
FORCEPROP 2 LAST SEC_TYPE 3018
J 0
(-2235 2810);
DISPLAY 1.021277 (-2235 2810);
PAINT ORANGE (-2235 2810);
DISPLAY INVISIBLE (-2235 2810);
FORCEPROP 2 LAST SEC 1
J 0
(-2250 2800);
PAINT MONO (-2250 2800);
DISPLAY INVISIBLE (-2250 2800);
FORCEPROP 2 LAST BOM_COST PROC_VRD_VCCIN_CPU0
J 0
(-2250 2750);
PAINT MONO (-2250 2750);
DISPLAY INVISIBLE (-2250 2750);
FORCEPROP 1 LAST PATH I29
J 0
(-2250 2750);
DISPLAY 0.978723 (-2250 2750);
PAINT ORANGE (-2250 2750);
DISPLAY INVISIBLE (-2250 2750);
FORCEPROP 2 LAST ROOM PVCCIN_CPU0_DECAP_VR
J 0
(-2250 2725);
PAINT MONO (-2250 2725);
DISPLAY INVISIBLE (-2250 2725);
FORCEPROP 2 LAST CDS_LOCATION C6P14
J 0
(-2250 2700);
DISPLAY 0.617021 (-2250 2700);
PAINT AQUA (-2250 2700);
DISPLAY INVISIBLE (-2250 2700);
FORCEPROP 2 LAST CDS_LIB mstr_discrete
J 0
(-2300 2600);
PAINT MONO (-2300 2600);
DISPLAY INVISIBLE (-2300 2600);
FORCEADD CAP..1
R 2
(-5875 825);
FORCEPROP 1 LAST LOCATION C4D9
J 2
(-5925 925);
DISPLAY 0.617021 (-5925 925);
PAINT AQUA (-5925 925);
FORCEPROP 1 LAST VALUE 0.220UF
J 2
(-5925 875);
DISPLAY 0.617021 (-5925 875);
PAINT SKYBLUE (-5925 875);
FORCEPROP 1 LAST PART_NUMBER A36096-104
J 2
(-5925 675);
DISPLAY 0.617021 (-5925 675);
PAINT BLUE (-5925 675);
FORCEPROP 1 LASTPIN (-5875 725) $PN 2
J 2
(-5885 705);
DISPLAY 0.617021 (-5885 705);
PAINT ORANGE (-5885 705);
FORCEPROP 1 LAST PACK_TYPE 0402
J 2
(-5925 625);
DISPLAY 0.617021 (-5925 625);
PAINT SKYBLUE (-5925 625);
FORCEPROP 1 LAST VOLTAGE 16V
J 2
(-5925 825);
DISPLAY 0.617021 (-5925 825);
PAINT SKYBLUE (-5925 825);
FORCEPROP 1 LAST TOLERANCE 10%
J 2
(-5925 775);
DISPLAY 0.617021 (-5925 775);
PAINT SKYBLUE (-5925 775);
FORCEPROP 1 LASTPIN (-5875 925) $PN 1
J 2
(-5885 905);
DISPLAY 0.617021 (-5885 905);
PAINT ORANGE (-5885 905);
FORCEPROP 1 LAST MATERIAL X7R
J 2
(-5925 725);
DISPLAY 0.617021 (-5925 725);
PAINT SKYBLUE (-5925 725);
FORCEPROP 2 LAST NO_XNET_CONNECTION 1
J 0
(-5925 1025);
PAINT MONO (-5925 1025);
DISPLAY INVISIBLE (-5925 1025);
FORCEPROP 2 LAST SEC 1
J 0
(-5925 1025);
DISPLAY 0.680851 (-5925 1025);
PAINT MONO (-5925 1025);
DISPLAY INVISIBLE (-5925 1025);
FORCEPROP 2 LAST SEC_TYPE 0402
J 0
(-5925 1025);
DISPLAY 1.021277 (-5925 1025);
PAINT ORANGE (-5925 1025);
DISPLAY INVISIBLE (-5925 1025);
FORCEPROP 0 LAST SPOF TRUE
J 0
(-5925 1025);
DISPLAY 1.021277 (-5925 1025);
PAINT ORANGE (-5925 1025);
DISPLAY INVISIBLE (-5925 1025);
FORCEPROP 2 LAST ROOM PVCCIN_CPU0_PWR_VR
J 0
(-5925 975);
DISPLAY 1.361702 (-5925 975);
PAINT ORANGE (-5925 975);
DISPLAY INVISIBLE (-5925 975);
FORCEPROP 1 LAST PATH I3
J 2
(-5925 975);
DISPLAY 0.978723 (-5925 975);
PAINT WHITE (-5925 975);
DISPLAY INVISIBLE (-5925 975);
FORCEPROP 2 LAST CDS_LOCATION C4D9
J 2
(-5925 925);
DISPLAY 0.617021 (-5925 925);
PAINT AQUA (-5925 925);
DISPLAY INVISIBLE (-5925 925);
FORCEPROP 2 LAST CDS_LIB mstr_discrete
J 0
(-5875 825);
PAINT ORANGE (-5875 825);
DISPLAY INVISIBLE (-5875 825);
FORCEADD CAPP..1
(-2750 2600);
FORCEPROP 1 LAST VOLTAGE 2.5V
J 0
(-2700 2550);
DISPLAY 0.638298 (-2700 2550);
PAINT SKYBLUE (-2700 2550);
FORCEPROP 1 LAST TOLERANCE 20%
J 0
(-2700 2600);
DISPLAY 0.617021 (-2700 2600);
PAINT SKYBLUE (-2700 2600);
FORCEPROP 1 LAST VALUE 470UF
J 0
(-2700 2650);
DISPLAY 0.617021 (-2700 2650);
PAINT SKYBLUE (-2700 2650);
FORCEPROP 1 LASTPIN (-2750 2700) $PN 1
J 0
(-2740 2685);
DISPLAY 0.617021 (-2740 2685);
PAINT GREEN (-2740 2685);
FORCEPROP 1 LAST PACK_TYPE 3018
J 0
(-2700 2450);
DISPLAY 0.617021 (-2700 2450);
PAINT SKYBLUE (-2700 2450);
FORCEPROP 1 LASTPIN (-2750 2500) $PN 2
J 0
(-2740 2485);
DISPLAY 0.617021 (-2740 2485);
PAINT GREEN (-2740 2485);
FORCEPROP 1 LAST MATERIAL ALUM
J 0
(-2700 2500);
DISPLAY 0.617021 (-2700 2500);
PAINT SKYBLUE (-2700 2500);
FORCEPROP 1 LAST LOCATION C6P18
J 0
(-2700 2700);
DISPLAY 0.617021 (-2700 2700);
PAINT AQUA (-2700 2700);
FORCEPROP 0 LAST GROUP PWR_BULK_CAP
J 0
(-2700 2350);
DISPLAY 0.638298 (-2700 2350);
PAINT BROWN (-2700 2350);
DISPLAY BOTH (-2700 2350);
FORCEPROP 1 LAST PART_NUMBER 699013-049
J 0
(-2700 2400);
DISPLAY 0.617021 (-2700 2400);
PAINT BLUE (-2700 2400);
FORCEPROP 2 LAST SEC_TYPE 3018
J 0
(-2685 2810);
DISPLAY 1.021277 (-2685 2810);
PAINT ORANGE (-2685 2810);
DISPLAY INVISIBLE (-2685 2810);
FORCEPROP 2 LAST SEC 1
J 0
(-2700 2800);
PAINT MONO (-2700 2800);
DISPLAY INVISIBLE (-2700 2800);
FORCEPROP 2 LAST BOM_COST PROC_VRD_VCCIN_CPU0
J 0
(-2700 2750);
PAINT MONO (-2700 2750);
DISPLAY INVISIBLE (-2700 2750);
FORCEPROP 2 LAST CDS_LOCATION C6P18
J 0
(-2700 2700);
DISPLAY 0.617021 (-2700 2700);
PAINT AQUA (-2700 2700);
DISPLAY INVISIBLE (-2700 2700);
FORCEPROP 1 LAST PATH I30
J 0
(-2700 2750);
DISPLAY 0.978723 (-2700 2750);
PAINT ORANGE (-2700 2750);
DISPLAY INVISIBLE (-2700 2750);
FORCEPROP 2 LAST ROOM PVCCIN_CPU0_DECAP_VR
J 0
(-2700 2725);
PAINT MONO (-2700 2725);
DISPLAY INVISIBLE (-2700 2725);
FORCEPROP 2 LAST CDS_LIB mstr_discrete
J 0
(-2750 2600);
PAINT MONO (-2750 2600);
DISPLAY INVISIBLE (-2750 2600);
FORCEADD CAPP..1
(-3200 2600);
FORCEPROP 1 LAST VALUE 470UF
J 0
(-3150 2650);
DISPLAY 0.617021 (-3150 2650);
PAINT SKYBLUE (-3150 2650);
FORCEPROP 1 LAST PART_NUMBER 699013-049
J 0
(-3150 2400);
DISPLAY 0.617021 (-3150 2400);
PAINT BLUE (-3150 2400);
FORCEPROP 1 LAST MATERIAL ALUM
J 0
(-3150 2500);
DISPLAY 0.617021 (-3150 2500);
PAINT SKYBLUE (-3150 2500);
FORCEPROP 1 LAST PACK_TYPE 3018
J 0
(-3150 2450);
DISPLAY 0.617021 (-3150 2450);
PAINT SKYBLUE (-3150 2450);
FORCEPROP 1 LAST LOCATION C6P8
J 0
(-3150 2700);
DISPLAY 0.617021 (-3150 2700);
PAINT AQUA (-3150 2700);
FORCEPROP 1 LASTPIN (-3200 2700) $PN 1
J 0
(-3190 2685);
DISPLAY 0.617021 (-3190 2685);
PAINT GREEN (-3190 2685);
FORCEPROP 1 LAST TOLERANCE 20%
J 0
(-3150 2600);
DISPLAY 0.617021 (-3150 2600);
PAINT SKYBLUE (-3150 2600);
FORCEPROP 1 LASTPIN (-3200 2500) $PN 2
J 0
(-3190 2485);
DISPLAY 0.617021 (-3190 2485);
PAINT GREEN (-3190 2485);
FORCEPROP 1 LAST VOLTAGE 2.5V
J 0
(-3150 2550);
DISPLAY 0.638298 (-3150 2550);
PAINT SKYBLUE (-3150 2550);
FORCEPROP 0 LAST GROUP PWR_BULK_CAP
J 0
(-3150 2300);
DISPLAY 0.638298 (-3150 2300);
PAINT BROWN (-3150 2300);
DISPLAY BOTH (-3150 2300);
FORCEPROP 2 LAST SEC_TYPE 3018
J 0
(-3135 2810);
DISPLAY 1.021277 (-3135 2810);
PAINT ORANGE (-3135 2810);
DISPLAY INVISIBLE (-3135 2810);
FORCEPROP 2 LAST SEC 1
J 0
(-3150 2800);
PAINT MONO (-3150 2800);
DISPLAY INVISIBLE (-3150 2800);
FORCEPROP 2 LAST BOM_COST PROC_VRD_VCCIN_CPU0
J 0
(-3150 2750);
PAINT MONO (-3150 2750);
DISPLAY INVISIBLE (-3150 2750);
FORCEPROP 1 LAST PATH I32
J 0
(-3150 2750);
DISPLAY 0.978723 (-3150 2750);
PAINT ORANGE (-3150 2750);
DISPLAY INVISIBLE (-3150 2750);
FORCEPROP 2 LAST ROOM PVCCIN_CPU0_DECAP_VR
J 0
(-3150 2725);
PAINT MONO (-3150 2725);
DISPLAY INVISIBLE (-3150 2725);
FORCEPROP 2 LAST CDS_LOCATION C6P8
J 0
(-3150 2700);
DISPLAY 0.617021 (-3150 2700);
PAINT AQUA (-3150 2700);
DISPLAY INVISIBLE (-3150 2700);
FORCEPROP 2 LAST CDS_LIB mstr_discrete
J 0
(-3200 2600);
PAINT MONO (-3200 2600);
DISPLAY INVISIBLE (-3200 2600);
FORCEADD PVCCIN_CPU0..1
(-3625 2875);
FORCEPROP 3 LASTPIN (-3625 2825) SIG_NAME PVCCIN_CPU0\g
J 0
(-3615 2835);
DISPLAY 0.659574 (-3615 2835);
PAINT MONO (-3615 2835);
DISPLAY INVISIBLE (-3615 2835);
FORCEPROP 1 LAST HDL_POWER PVCCIN_CPU0
J 1
(-3625 2925);
DISPLAY 0.872340 (-3625 2925);
PAINT GREEN (-3625 2925);
DISPLAY INVISIBLE (-3625 2925);
FORCEPROP 1 LAST BODY_TYPE PLUMBING
J 0
(-3670 2832);
DISPLAY 0.340426 (-3670 2832);
PAINT GREEN (-3670 2832);
DISPLAY INVISIBLE (-3670 2832);
FORCEPROP 1 LAST PATH I33
J 0
(-3575 2900);
DISPLAY 0.872340 (-3575 2900);
PAINT AQUA (-3575 2900);
DISPLAY INVISIBLE (-3575 2900);
FORCEPROP 2 LAST CDS_LIB mstr_symbols
J 0
(-3625 2875);
PAINT ORANGE (-3625 2875);
DISPLAY INVISIBLE (-3625 2875);
FORCEPROP 1 LAST VOLTAGE 2.0V
J 0
(-3670 2832);
DISPLAY 0.340426 (-3670 2832);
PAINT SKYBLUE (-3670 2832);
DISPLAY INVISIBLE (-3670 2832);
FORCEADD CAPP..1
(-3625 2600);
FORCEPROP 1 LASTPIN (-3625 2700) $PN 1
J 0
(-3615 2685);
DISPLAY 0.617021 (-3615 2685);
PAINT GREEN (-3615 2685);
FORCEPROP 1 LAST VOLTAGE 2.5V
J 0
(-3575 2550);
DISPLAY 0.617021 (-3575 2550);
PAINT SKYBLUE (-3575 2550);
FORCEPROP 1 LAST MATERIAL ALUM
J 0
(-3575 2500);
DISPLAY 0.617021 (-3575 2500);
PAINT SKYBLUE (-3575 2500);
FORCEPROP 1 LAST PACK_TYPE 3018
J 0
(-3575 2450);
DISPLAY 0.617021 (-3575 2450);
PAINT SKYBLUE (-3575 2450);
FORCEPROP 1 LASTPIN (-3625 2500) $PN 2
J 0
(-3615 2485);
DISPLAY 0.617021 (-3615 2485);
PAINT GREEN (-3615 2485);
FORCEPROP 1 LAST TOLERANCE 20%
J 0
(-3575 2600);
DISPLAY 0.617021 (-3575 2600);
PAINT SKYBLUE (-3575 2600);
FORCEPROP 1 LAST VALUE 470UF
J 0
(-3575 2650);
DISPLAY 0.617021 (-3575 2650);
PAINT SKYBLUE (-3575 2650);
FORCEPROP 1 LAST LOCATION C6N9
J 0
(-3575 2700);
DISPLAY 0.617021 (-3575 2700);
PAINT AQUA (-3575 2700);
FORCEPROP 1 LAST PART_NUMBER 699013-049
J 0
(-3575 2400);
DISPLAY 0.617021 (-3575 2400);
PAINT BLUE (-3575 2400);
FORCEPROP 0 LAST GROUP PWR_BULK_CAP
J 0
(-3575 2350);
DISPLAY 0.638298 (-3575 2350);
PAINT BROWN (-3575 2350);
DISPLAY BOTH (-3575 2350);
FORCEPROP 2 LAST SEC_TYPE 3018
J 0
(-3560 2810);
DISPLAY 1.021277 (-3560 2810);
PAINT ORANGE (-3560 2810);
DISPLAY INVISIBLE (-3560 2810);
FORCEPROP 2 LAST BOM_COST PROC_VRD_VCCIN_CPU0
J 0
(-3575 2750);
PAINT MONO (-3575 2750);
DISPLAY INVISIBLE (-3575 2750);
FORCEPROP 2 LAST SEC 1
J 0
(-3575 2800);
PAINT MONO (-3575 2800);
DISPLAY INVISIBLE (-3575 2800);
FORCEPROP 2 LAST CDS_LOCATION C6N9
J 0
(-3575 2700);
DISPLAY 0.617021 (-3575 2700);
PAINT AQUA (-3575 2700);
DISPLAY INVISIBLE (-3575 2700);
FORCEPROP 1 LAST PATH I34
J 0
(-3575 2750);
DISPLAY 0.978723 (-3575 2750);
PAINT ORANGE (-3575 2750);
DISPLAY INVISIBLE (-3575 2750);
FORCEPROP 2 LAST ROOM PVCCIN_CPU0_DECAP_VR
J 0
(-3575 2725);
PAINT MONO (-3575 2725);
DISPLAY INVISIBLE (-3575 2725);
FORCEPROP 2 LAST CDS_LIB mstr_discrete
J 0
(-3625 2600);
PAINT MONO (-3625 2600);
DISPLAY INVISIBLE (-3625 2600);
FORCEADD VCC_CORE..1
(-6550 4600);
FORCEPROP 3 LASTPIN (-6550 4550) SIG_NAME VR_FET_SW_P12V_STBY_PVCCIN_CPU0\g
J 0
(-6540 4560);
DISPLAY 0.659574 (-6540 4560);
PAINT MONO (-6540 4560);
DISPLAY INVISIBLE (-6540 4560);
FORCEPROP 1 LAST HDL_POWER VR_FET_SW_P12V_STBY_PVCCIN_CPU0
J 1
(-6500 4650);
DISPLAY 0.617021 (-6500 4650);
PAINT GREEN (-6500 4650);
FORCEPROP 2 LAST CDS_LIB mstr_symbols
J 0
(-6550 4600);
DISPLAY 1.936170 (-6550 4600);
PAINT ORANGE (-6550 4600);
DISPLAY INVISIBLE (-6550 4600);
FORCEPROP 1 LAST PATH I39
J 0
(-6500 4625);
DISPLAY 0.872340 (-6500 4625);
PAINT AQUA (-6500 4625);
DISPLAY INVISIBLE (-6500 4625);
FORCEADD CAP..1
(-4600 4150);
FORCEPROP 1 LAST MATERIAL X7R
J 0
(-4550 4050);
DISPLAY 0.617021 (-4550 4050);
PAINT SKYBLUE (-4550 4050);
FORCEPROP 1 LASTPIN (-4600 4250) $PN 1
J 0
(-4590 4230);
DISPLAY 0.617021 (-4590 4230);
PAINT ORANGE (-4590 4230);
FORCEPROP 1 LASTPIN (-4600 4050) $PN 2
J 0
(-4590 4030);
DISPLAY 0.617021 (-4590 4030);
PAINT ORANGE (-4590 4030);
FORCEPROP 1 LAST LOCATION C4D13
J 0
(-4550 4250);
DISPLAY 0.617021 (-4550 4250);
PAINT AQUA (-4550 4250);
FORCEPROP 1 LAST VALUE 0.22UF
J 0
(-4550 4200);
DISPLAY 0.617021 (-4550 4200);
PAINT SKYBLUE (-4550 4200);
FORCEPROP 1 LAST VOLTAGE 16V
J 0
(-4550 4150);
DISPLAY 0.617021 (-4550 4150);
PAINT SKYBLUE (-4550 4150);
FORCEPROP 1 LAST TOLERANCE 10%
J 0
(-4550 4100);
DISPLAY 0.617021 (-4550 4100);
PAINT SKYBLUE (-4550 4100);
FORCEPROP 1 LAST PART_NUMBER A36096-155
J 0
(-4550 4000);
DISPLAY 0.617021 (-4550 4000);
PAINT BLUE (-4550 4000);
FORCEPROP 1 LAST PACK_TYPE 0402
J 0
(-4550 3950);
DISPLAY 0.617021 (-4550 3950);
PAINT SKYBLUE (-4550 3950);
FORCEPROP 2 LAST SEC_TYPE 0402
J 0
(-4550 4350);
DISPLAY 1.021277 (-4550 4350);
PAINT ORANGE (-4550 4350);
DISPLAY INVISIBLE (-4550 4350);
FORCEPROP 2 LAST CDS_LIB mstr_discrete
J 0
(-4600 4150);
PAINT ORANGE (-4600 4150);
DISPLAY INVISIBLE (-4600 4150);
FORCEPROP 2 LAST SEC 1
J 0
(-4550 4350);
DISPLAY 0.680851 (-4550 4350);
PAINT MONO (-4550 4350);
DISPLAY INVISIBLE (-4550 4350);
FORCEPROP 2 LAST CDS_LOCATION C4D13
J 0
(-4550 4250);
DISPLAY 0.617021 (-4550 4250);
PAINT AQUA (-4550 4250);
DISPLAY INVISIBLE (-4550 4250);
FORCEPROP 1 LAST PATH I40
J 0
(-4550 4300);
DISPLAY 0.978723 (-4550 4300);
PAINT WHITE (-4550 4300);
DISPLAY INVISIBLE (-4550 4300);
FORCEPROP 2 LAST ROOM PVCCIN_CPU0_PWR_VR
J 0
(-4550 4300);
DISPLAY 1.361702 (-4550 4300);
PAINT ORANGE (-4550 4300);
DISPLAY INVISIBLE (-4550 4300);
FORCEADD CAP..1
R 2
(-5800 3550);
FORCEPROP 1 LAST LOCATION C4D28
J 2
(-5850 3650);
DISPLAY 0.617021 (-5850 3650);
PAINT AQUA (-5850 3650);
FORCEPROP 1 LAST VALUE 0.220UF
J 2
(-5850 3600);
DISPLAY 0.617021 (-5850 3600);
PAINT SKYBLUE (-5850 3600);
FORCEPROP 1 LASTPIN (-5800 3650) $PN 1
J 2
(-5810 3630);
DISPLAY 0.617021 (-5810 3630);
PAINT ORANGE (-5810 3630);
FORCEPROP 1 LASTPIN (-5800 3450) $PN 2
J 2
(-5810 3430);
DISPLAY 0.617021 (-5810 3430);
PAINT ORANGE (-5810 3430);
FORCEPROP 1 LAST VOLTAGE 16V
J 2
(-5850 3550);
DISPLAY 0.617021 (-5850 3550);
PAINT SKYBLUE (-5850 3550);
FORCEPROP 1 LAST TOLERANCE 10%
J 2
(-5850 3500);
DISPLAY 0.617021 (-5850 3500);
PAINT SKYBLUE (-5850 3500);
FORCEPROP 1 LAST MATERIAL X7R
J 2
(-5850 3450);
DISPLAY 0.617021 (-5850 3450);
PAINT SKYBLUE (-5850 3450);
FORCEPROP 1 LAST PART_NUMBER A36096-104
J 2
(-5850 3400);
DISPLAY 0.617021 (-5850 3400);
PAINT BLUE (-5850 3400);
FORCEPROP 1 LAST PACK_TYPE 0402
J 2
(-5850 3350);
DISPLAY 0.617021 (-5850 3350);
PAINT SKYBLUE (-5850 3350);
FORCEPROP 2 LAST NO_XNET_CONNECTION 1
J 0
(-5850 3750);
PAINT MONO (-5850 3750);
DISPLAY INVISIBLE (-5850 3750);
FORCEPROP 1 LAST PATH I42
J 2
(-5850 3700);
DISPLAY 0.978723 (-5850 3700);
PAINT WHITE (-5850 3700);
DISPLAY INVISIBLE (-5850 3700);
FORCEPROP 2 LAST ROOM PVCCIN_CPU0_PWR_VR
J 0
(-5875 3700);
DISPLAY 1.361702 (-5875 3700);
PAINT ORANGE (-5875 3700);
DISPLAY INVISIBLE (-5875 3700);
FORCEPROP 2 LAST CDS_LOCATION C4D28
J 2
(-5850 3650);
DISPLAY 0.617021 (-5850 3650);
PAINT AQUA (-5850 3650);
DISPLAY INVISIBLE (-5850 3650);
FORCEPROP 2 LAST SEC 1
J 0
(-5850 3750);
DISPLAY 0.680851 (-5850 3750);
PAINT MONO (-5850 3750);
DISPLAY INVISIBLE (-5850 3750);
FORCEPROP 0 LAST SPOF TRUE
J 0
(-5850 3750);
DISPLAY 1.021277 (-5850 3750);
PAINT ORANGE (-5850 3750);
DISPLAY INVISIBLE (-5850 3750);
FORCEPROP 2 LAST SEC_TYPE 0402
J 0
(-5850 3750);
DISPLAY 1.021277 (-5850 3750);
PAINT ORANGE (-5850 3750);
DISPLAY INVISIBLE (-5850 3750);
FORCEPROP 2 LAST CDS_LIB mstr_discrete
J 0
(-5800 3550);
PAINT ORANGE (-5800 3550);
DISPLAY INVISIBLE (-5800 3550);
FORCEADD CAP..1
(-5475 4150);
FORCEPROP 1 LASTPIN (-5475 4250) $PN 1
J 0
(-5465 4230);
DISPLAY 0.617021 (-5465 4230);
PAINT ORANGE (-5465 4230);
FORCEPROP 1 LAST VALUE 1.0UF
J 0
(-5425 4200);
DISPLAY 0.617021 (-5425 4200);
PAINT SKYBLUE (-5425 4200);
FORCEPROP 1 LAST TOLERANCE 10%
J 0
(-5425 4100);
DISPLAY 0.617021 (-5425 4100);
PAINT SKYBLUE (-5425 4100);
FORCEPROP 1 LAST MATERIAL X6S
J 0
(-5425 4050);
DISPLAY 0.617021 (-5425 4050);
PAINT SKYBLUE (-5425 4050);
FORCEPROP 1 LAST PACK_TYPE 0402
J 0
(-5425 3950);
DISPLAY 0.617021 (-5425 3950);
PAINT SKYBLUE (-5425 3950);
FORCEPROP 1 LASTPIN (-5475 4050) $PN 2
J 0
(-5465 4030);
DISPLAY 0.617021 (-5465 4030);
PAINT ORANGE (-5465 4030);
FORCEPROP 1 LAST PART_NUMBER D97712-011
J 0
(-5425 4000);
DISPLAY 0.617021 (-5425 4000);
PAINT BLUE (-5425 4000);
FORCEPROP 1 LAST VOLTAGE 16V
J 0
(-5425 4150);
DISPLAY 0.617021 (-5425 4150);
PAINT SKYBLUE (-5425 4150);
FORCEPROP 1 LAST LOCATION C4D16
J 0
(-5425 4250);
DISPLAY 0.617021 (-5425 4250);
PAINT AQUA (-5425 4250);
FORCEPROP 2 LAST SEC_TYPE 0402
J 0
(-5425 4350);
DISPLAY 1.021277 (-5425 4350);
PAINT ORANGE (-5425 4350);
DISPLAY INVISIBLE (-5425 4350);
FORCEPROP 2 LAST SEC 1
J 0
(-5425 4350);
DISPLAY 0.680851 (-5425 4350);
PAINT MONO (-5425 4350);
DISPLAY INVISIBLE (-5425 4350);
FORCEPROP 2 LAST CDS_LIB mstr_discrete
J 0
(-5475 4150);
PAINT ORANGE (-5475 4150);
DISPLAY INVISIBLE (-5475 4150);
FORCEPROP 2 LAST CDS_LOCATION C4D16
J 0
(-5425 4250);
DISPLAY 0.617021 (-5425 4250);
PAINT AQUA (-5425 4250);
DISPLAY INVISIBLE (-5425 4250);
FORCEPROP 1 LAST PATH I45
J 0
(-5425 4300);
DISPLAY 0.978723 (-5425 4300);
PAINT WHITE (-5425 4300);
DISPLAY INVISIBLE (-5425 4300);
FORCEPROP 2 LAST ROOM PVCCIN_CPU0_PWR_VR
J 0
(-5425 4300);
DISPLAY 1.361702 (-5425 4300);
PAINT ORANGE (-5425 4300);
DISPLAY INVISIBLE (-5425 4300);
FORCEADD CAP_A..1
(-5775 4150);
FORCEPROP 1 LASTPIN (-5775 4250) $PN 1
J 0
(-5765 4230);
DISPLAY 0.617021 (-5765 4230);
PAINT ORANGE (-5765 4230);
FORCEPROP 1 LAST LOCATION C4D35
J 0
(-5725 4250);
DISPLAY 0.617021 (-5725 4250);
PAINT AQUA (-5725 4250);
FORCEPROP 1 LAST TOLERANCE 10%
J 0
(-5725 4100);
DISPLAY 0.617021 (-5725 4100);
PAINT SKYBLUE (-5725 4100);
FORCEPROP 1 LAST MATERIAL X7R
J 0
(-5725 4050);
DISPLAY 0.617021 (-5725 4050);
PAINT SKYBLUE (-5725 4050);
FORCEPROP 1 LASTPIN (-5775 4050) $PN 2
J 0
(-5765 4030);
DISPLAY 0.617021 (-5765 4030);
PAINT ORANGE (-5765 4030);
FORCEPROP 1 LAST PART_NUMBER A36096-030
J 0
(-5725 4000);
DISPLAY 0.617021 (-5725 4000);
PAINT BLUE (-5725 4000);
FORCEPROP 1 LAST VALUE 0.1UF
J 0
(-5725 4200);
DISPLAY 0.617021 (-5725 4200);
PAINT SKYBLUE (-5725 4200);
FORCEPROP 1 LAST VOLTAGE 16V
J 0
(-5725 4150);
DISPLAY 0.617021 (-5725 4150);
PAINT SKYBLUE (-5725 4150);
FORCEPROP 1 LAST PACK_TYPE 0402V
J 0
(-5725 3950);
DISPLAY 0.617021 (-5725 3950);
PAINT SKYBLUE (-5725 3950);
FORCEPROP 2 LAST SEC 1
J 0
(-5725 4350);
DISPLAY 0.680851 (-5725 4350);
PAINT MONO (-5725 4350);
DISPLAY INVISIBLE (-5725 4350);
FORCEPROP 2 LAST SEC_TYPE 0402V
J 0
(-5725 4350);
DISPLAY 1.021277 (-5725 4350);
PAINT ORANGE (-5725 4350);
DISPLAY INVISIBLE (-5725 4350);
FORCEPROP 2 LAST ROOM PVCCIN_CPU0_PWR_VR
J 0
(-5725 4300);
DISPLAY 1.361702 (-5725 4300);
PAINT ORANGE (-5725 4300);
DISPLAY INVISIBLE (-5725 4300);
FORCEPROP 2 LAST CDS_SEC 1
J 0
(-5725 4300);
PAINT ORANGE (-5725 4300);
DISPLAY INVISIBLE (-5725 4300);
FORCEPROP 2 LAST CDS_LOCATION C4D35
J 0
(-5725 4250);
DISPLAY 0.617021 (-5725 4250);
PAINT AQUA (-5725 4250);
DISPLAY INVISIBLE (-5725 4250);
FORCEPROP 1 LAST PATH I46
J 0
(-5725 4300);
DISPLAY 0.978723 (-5725 4300);
PAINT WHITE (-5725 4300);
DISPLAY INVISIBLE (-5725 4300);
FORCEPROP 2 LAST CDS_LIB dev_discrete
J 0
(-5775 4150);
PAINT ORANGE (-5775 4150);
DISPLAY INVISIBLE (-5775 4150);
FORCEADD CAP..1
(-6050 4150);
FORCEPROP 1 LASTPIN (-6050 4250) $PN 1
J 0
(-6040 4230);
DISPLAY 0.617021 (-6040 4230);
PAINT ORANGE (-6040 4230);
FORCEPROP 1 LAST TOLERANCE 10%
J 0
(-6000 4100);
DISPLAY 0.617021 (-6000 4100);
PAINT SKYBLUE (-6000 4100);
FORCEPROP 1 LAST VALUE 1.0UF
J 0
(-6000 4200);
DISPLAY 0.617021 (-6000 4200);
PAINT SKYBLUE (-6000 4200);
FORCEPROP 1 LAST LOCATION C4D30
J 0
(-6000 4250);
DISPLAY 0.617021 (-6000 4250);
PAINT AQUA (-6000 4250);
FORCEPROP 1 LASTPIN (-6050 4050) $PN 2
J 0
(-6040 4030);
DISPLAY 0.617021 (-6040 4030);
PAINT ORANGE (-6040 4030);
FORCEPROP 1 LAST MATERIAL X6S
J 0
(-6000 4050);
DISPLAY 0.617021 (-6000 4050);
PAINT SKYBLUE (-6000 4050);
FORCEPROP 1 LAST VOLTAGE 16V
J 0
(-6000 4150);
DISPLAY 0.617021 (-6000 4150);
PAINT SKYBLUE (-6000 4150);
FORCEPROP 1 LAST PART_NUMBER D97712-011
J 0
(-6025 4000);
DISPLAY 0.617021 (-6025 4000);
PAINT BLUE (-6025 4000);
FORCEPROP 1 LAST PACK_TYPE 0402
J 0
(-6000 3950);
DISPLAY 0.617021 (-6000 3950);
PAINT SKYBLUE (-6000 3950);
FORCEPROP 2 LAST ROOM PVCCIN_CPU0_PWR_VR
J 0
(-6000 4300);
DISPLAY 1.361702 (-6000 4300);
PAINT ORANGE (-6000 4300);
DISPLAY INVISIBLE (-6000 4300);
FORCEPROP 2 LAST SEC 1
J 0
(-6000 4350);
DISPLAY 0.680851 (-6000 4350);
PAINT MONO (-6000 4350);
DISPLAY INVISIBLE (-6000 4350);
FORCEPROP 2 LAST SEC_TYPE 0402
J 0
(-6000 4350);
DISPLAY 1.021277 (-6000 4350);
PAINT ORANGE (-6000 4350);
DISPLAY INVISIBLE (-6000 4350);
FORCEPROP 2 LAST CDS_LIB mstr_discrete
J 0
(-6050 4150);
PAINT ORANGE (-6050 4150);
DISPLAY INVISIBLE (-6050 4150);
FORCEPROP 2 LAST CDS_LOCATION C4D30
J 0
(-6000 4250);
DISPLAY 0.617021 (-6000 4250);
PAINT AQUA (-6000 4250);
DISPLAY INVISIBLE (-6000 4250);
FORCEPROP 1 LAST PATH I47
J 0
(-6000 4300);
DISPLAY 0.978723 (-6000 4300);
PAINT WHITE (-6000 4300);
DISPLAY INVISIBLE (-6000 4300);
FORCEADD CAP..1
(-4825 1475);
FORCEPROP 1 LAST TOLERANCE 10%
J 0
(-4775 1425);
DISPLAY 0.617021 (-4775 1425);
PAINT SKYBLUE (-4775 1425);
FORCEPROP 1 LAST MATERIAL X7R
J 0
(-4775 1375);
DISPLAY 0.617021 (-4775 1375);
PAINT SKYBLUE (-4775 1375);
FORCEPROP 1 LASTPIN (-4825 1575) $PN 1
J 0
(-4815 1555);
DISPLAY 0.617021 (-4815 1555);
PAINT ORANGE (-4815 1555);
FORCEPROP 1 LASTPIN (-4825 1375) $PN 2
J 0
(-4815 1355);
DISPLAY 0.617021 (-4815 1355);
PAINT ORANGE (-4815 1355);
FORCEPROP 1 LAST PACK_TYPE 0402
J 0
(-4775 1275);
DISPLAY 0.617021 (-4775 1275);
PAINT SKYBLUE (-4775 1275);
FORCEPROP 1 LAST VALUE 0.22UF
J 0
(-4775 1525);
DISPLAY 0.617021 (-4775 1525);
PAINT SKYBLUE (-4775 1525);
FORCEPROP 1 LAST LOCATION C4D5
J 0
(-4775 1575);
DISPLAY 0.617021 (-4775 1575);
PAINT AQUA (-4775 1575);
FORCEPROP 1 LAST VOLTAGE 16V
J 0
(-4775 1475);
DISPLAY 0.617021 (-4775 1475);
PAINT SKYBLUE (-4775 1475);
FORCEPROP 1 LAST PART_NUMBER A36096-155
J 0
(-4775 1325);
DISPLAY 0.617021 (-4775 1325);
PAINT BLUE (-4775 1325);
FORCEPROP 2 LAST SEC_TYPE 0402
J 0
(-4775 1675);
DISPLAY 1.021277 (-4775 1675);
PAINT ORANGE (-4775 1675);
DISPLAY INVISIBLE (-4775 1675);
FORCEPROP 2 LAST SEC 1
J 0
(-4775 1675);
DISPLAY 0.680851 (-4775 1675);
PAINT MONO (-4775 1675);
DISPLAY INVISIBLE (-4775 1675);
FORCEPROP 2 LAST CDS_LOCATION C4D5
J 0
(-4775 1575);
DISPLAY 0.617021 (-4775 1575);
PAINT AQUA (-4775 1575);
DISPLAY INVISIBLE (-4775 1575);
FORCEPROP 1 LAST PATH I48
J 0
(-4775 1625);
DISPLAY 0.978723 (-4775 1625);
PAINT WHITE (-4775 1625);
DISPLAY INVISIBLE (-4775 1625);
FORCEPROP 2 LAST ROOM PVCCIN_CPU0_PWR_VR
J 0
(-4775 1625);
DISPLAY 1.361702 (-4775 1625);
PAINT ORANGE (-4775 1625);
DISPLAY INVISIBLE (-4775 1625);
FORCEPROP 2 LAST CDS_LIB mstr_discrete
J 0
(-4825 1475);
PAINT ORANGE (-4825 1475);
DISPLAY INVISIBLE (-4825 1475);
FORCEADD OFFPAGE..2
(-800 4850);
FORCEPROP 2 LAST $XR0 201 
J 0
(-611 4850);
DISPLAY 0.638298 (-611 4850);
PAINT MONO (-611 4850);
FORCEPROP 1 LAST COMMENT_BODY TRUE
J 0
(-845 4755);
DISPLAY 1.723404 (-845 4755);
PAINT GREEN (-845 4755);
DISPLAY INVISIBLE (-845 4755);
FORCEPROP 1 LAST OFFPAGE TRUE
J 0
(-475 4725);
DISPLAY 1.723404 (-475 4725);
PAINT GREEN (-475 4725);
DISPLAY INVISIBLE (-475 4725);
FORCEPROP 2 LAST ROOM PVCCIN_CPU0_PWR_VR
J 0
(-1200 4925);
DISPLAY 1.936170 (-1200 4925);
PAINT ORANGE (-1200 4925);
DISPLAY INVISIBLE (-1200 4925);
FORCEPROP 2 LAST CDS_LIB mstr_standard
J 2
(-800 4850);
DISPLAY 1.936170 (-800 4850);
PAINT ORANGE (-800 4850);
DISPLAY INVISIBLE (-800 4850);
FORCEPROP 2 LAST PATH I5
J 0
(-625 4925);
DISPLAY 1.021277 (-625 4925);
PAINT ORANGE (-625 4925);
DISPLAY INVISIBLE (-625 4925);
FORCEPROP 2 LAST BOM_COST PROC_VRD_VCCIN_CPU0
J 0
(-600 4900);
DISPLAY 1.446809 (-600 4900);
PAINT MONO (-600 4900);
DISPLAY INVISIBLE (-600 4900);
FORCEADD CAP..1
(-5675 1475);
FORCEPROP 1 LAST LOCATION C4D7
J 0
(-5625 1575);
DISPLAY 0.617021 (-5625 1575);
PAINT AQUA (-5625 1575);
FORCEPROP 1 LAST PART_NUMBER D97712-011
J 0
(-5625 1325);
DISPLAY 0.617021 (-5625 1325);
PAINT BLUE (-5625 1325);
FORCEPROP 1 LASTPIN (-5675 1575) $PN 1
J 0
(-5665 1555);
DISPLAY 0.617021 (-5665 1555);
PAINT ORANGE (-5665 1555);
FORCEPROP 1 LASTPIN (-5675 1375) $PN 2
J 0
(-5665 1355);
DISPLAY 0.617021 (-5665 1355);
PAINT ORANGE (-5665 1355);
FORCEPROP 1 LAST PACK_TYPE 0402
J 0
(-5625 1275);
DISPLAY 0.617021 (-5625 1275);
PAINT SKYBLUE (-5625 1275);
FORCEPROP 1 LAST MATERIAL X6S
J 0
(-5625 1375);
DISPLAY 0.617021 (-5625 1375);
PAINT SKYBLUE (-5625 1375);
FORCEPROP 1 LAST TOLERANCE 10%
J 0
(-5625 1425);
DISPLAY 0.617021 (-5625 1425);
PAINT SKYBLUE (-5625 1425);
FORCEPROP 1 LAST VALUE 1.0UF
J 0
(-5625 1525);
DISPLAY 0.617021 (-5625 1525);
PAINT SKYBLUE (-5625 1525);
FORCEPROP 1 LAST VOLTAGE 16V
J 0
(-5625 1475);
DISPLAY 0.617021 (-5625 1475);
PAINT SKYBLUE (-5625 1475);
FORCEPROP 2 LAST SEC_TYPE 0402
J 0
(-5625 1675);
DISPLAY 1.021277 (-5625 1675);
PAINT ORANGE (-5625 1675);
DISPLAY INVISIBLE (-5625 1675);
FORCEPROP 2 LAST SEC 1
J 0
(-5625 1675);
DISPLAY 0.680851 (-5625 1675);
PAINT MONO (-5625 1675);
DISPLAY INVISIBLE (-5625 1675);
FORCEPROP 2 LAST CDS_LOCATION C4D7
J 0
(-5625 1575);
DISPLAY 0.617021 (-5625 1575);
PAINT AQUA (-5625 1575);
DISPLAY INVISIBLE (-5625 1575);
FORCEPROP 1 LAST PATH I51
J 0
(-5625 1625);
DISPLAY 0.978723 (-5625 1625);
PAINT WHITE (-5625 1625);
DISPLAY INVISIBLE (-5625 1625);
FORCEPROP 2 LAST ROOM PVCCIN_CPU0_PWR_VR
J 0
(-5625 1625);
DISPLAY 1.361702 (-5625 1625);
PAINT ORANGE (-5625 1625);
DISPLAY INVISIBLE (-5625 1625);
FORCEPROP 2 LAST CDS_LIB mstr_discrete
J 0
(-5675 1475);
PAINT ORANGE (-5675 1475);
DISPLAY INVISIBLE (-5675 1475);
FORCEADD CAP_A..1
(-5975 1475);
FORCEPROP 1 LAST LOCATION C4D11
J 0
(-5925 1575);
DISPLAY 0.617021 (-5925 1575);
PAINT AQUA (-5925 1575);
FORCEPROP 1 LASTPIN (-5975 1575) $PN 1
J 0
(-5965 1555);
DISPLAY 0.617021 (-5965 1555);
PAINT ORANGE (-5965 1555);
FORCEPROP 1 LASTPIN (-5975 1375) $PN 2
J 0
(-5965 1355);
DISPLAY 0.617021 (-5965 1355);
PAINT ORANGE (-5965 1355);
FORCEPROP 1 LAST MATERIAL X7R
J 0
(-5925 1375);
DISPLAY 0.617021 (-5925 1375);
PAINT SKYBLUE (-5925 1375);
FORCEPROP 1 LAST PACK_TYPE 0402V
J 0
(-5925 1275);
DISPLAY 0.617021 (-5925 1275);
PAINT SKYBLUE (-5925 1275);
FORCEPROP 1 LAST TOLERANCE 10%
J 0
(-5925 1425);
DISPLAY 0.617021 (-5925 1425);
PAINT SKYBLUE (-5925 1425);
FORCEPROP 1 LAST PART_NUMBER A36096-030
J 0
(-5925 1325);
DISPLAY 0.617021 (-5925 1325);
PAINT BLUE (-5925 1325);
FORCEPROP 1 LAST VALUE 0.1UF
J 0
(-5925 1525);
DISPLAY 0.617021 (-5925 1525);
PAINT SKYBLUE (-5925 1525);
FORCEPROP 1 LAST VOLTAGE 16V
J 0
(-5925 1475);
DISPLAY 0.617021 (-5925 1475);
PAINT SKYBLUE (-5925 1475);
FORCEPROP 2 LAST CDS_LIB dev_discrete
J 0
(-5975 1475);
PAINT ORANGE (-5975 1475);
DISPLAY INVISIBLE (-5975 1475);
FORCEPROP 1 LAST PATH I52
J 0
(-5925 1625);
DISPLAY 0.978723 (-5925 1625);
PAINT WHITE (-5925 1625);
DISPLAY INVISIBLE (-5925 1625);
FORCEPROP 2 LAST ROOM PVCCIN_CPU0_PWR_VR
J 0
(-5925 1625);
DISPLAY 1.361702 (-5925 1625);
PAINT ORANGE (-5925 1625);
DISPLAY INVISIBLE (-5925 1625);
FORCEPROP 2 LAST CDS_LOCATION C4D11
J 0
(-5925 1575);
DISPLAY 0.617021 (-5925 1575);
PAINT AQUA (-5925 1575);
DISPLAY INVISIBLE (-5925 1575);
FORCEPROP 2 LAST CDS_SEC 1
J 0
(-5925 1625);
PAINT ORANGE (-5925 1625);
DISPLAY INVISIBLE (-5925 1625);
FORCEPROP 2 LAST SEC_TYPE 0402V
J 0
(-5925 1675);
DISPLAY 1.021277 (-5925 1675);
PAINT ORANGE (-5925 1675);
DISPLAY INVISIBLE (-5925 1675);
FORCEPROP 2 LAST SEC 1
J 0
(-5925 1675);
DISPLAY 0.680851 (-5925 1675);
PAINT MONO (-5925 1675);
DISPLAY INVISIBLE (-5925 1675);
FORCEADD CAP..1
(-6250 1475);
FORCEPROP 1 LAST LOCATION C4D10
J 0
(-6200 1575);
DISPLAY 0.617021 (-6200 1575);
PAINT AQUA (-6200 1575);
FORCEPROP 1 LASTPIN (-6250 1575) $PN 1
J 0
(-6240 1555);
DISPLAY 0.617021 (-6240 1555);
PAINT ORANGE (-6240 1555);
FORCEPROP 1 LAST PART_NUMBER D97712-011
J 0
(-6200 1325);
DISPLAY 0.617021 (-6200 1325);
PAINT BLUE (-6200 1325);
FORCEPROP 1 LAST VALUE 1.0UF
J 0
(-6200 1525);
DISPLAY 0.617021 (-6200 1525);
PAINT SKYBLUE (-6200 1525);
FORCEPROP 1 LAST VOLTAGE 16V
J 0
(-6200 1475);
DISPLAY 0.617021 (-6200 1475);
PAINT SKYBLUE (-6200 1475);
FORCEPROP 1 LAST MATERIAL X6S
J 0
(-6200 1375);
DISPLAY 0.617021 (-6200 1375);
PAINT SKYBLUE (-6200 1375);
FORCEPROP 1 LAST TOLERANCE 10%
J 0
(-6200 1425);
DISPLAY 0.617021 (-6200 1425);
PAINT SKYBLUE (-6200 1425);
FORCEPROP 1 LAST PACK_TYPE 0402
J 0
(-6200 1275);
DISPLAY 0.617021 (-6200 1275);
PAINT SKYBLUE (-6200 1275);
FORCEPROP 1 LASTPIN (-6250 1375) $PN 2
J 0
(-6240 1355);
DISPLAY 0.617021 (-6240 1355);
PAINT ORANGE (-6240 1355);
FORCEPROP 2 LAST ROOM PVCCIN_CPU0_PWR_VR
J 0
(-6200 1625);
DISPLAY 1.361702 (-6200 1625);
PAINT ORANGE (-6200 1625);
DISPLAY INVISIBLE (-6200 1625);
FORCEPROP 1 LAST PATH I53
J 0
(-6200 1625);
DISPLAY 0.978723 (-6200 1625);
PAINT WHITE (-6200 1625);
DISPLAY INVISIBLE (-6200 1625);
FORCEPROP 2 LAST SEC 1
J 0
(-6200 1675);
DISPLAY 0.680851 (-6200 1675);
PAINT MONO (-6200 1675);
DISPLAY INVISIBLE (-6200 1675);
FORCEPROP 2 LAST SEC_TYPE 0402
J 0
(-6200 1675);
DISPLAY 1.021277 (-6200 1675);
PAINT ORANGE (-6200 1675);
DISPLAY INVISIBLE (-6200 1675);
FORCEPROP 2 LAST CDS_LOCATION C4D10
J 0
(-6200 1575);
DISPLAY 0.617021 (-6200 1575);
PAINT AQUA (-6200 1575);
DISPLAY INVISIBLE (-6200 1575);
FORCEPROP 2 LAST CDS_LIB mstr_discrete
J 0
(-6250 1475);
PAINT ORANGE (-6250 1475);
DISPLAY INVISIBLE (-6250 1475);
FORCEADD CAP..1
(-7000 4175);
FORCEPROP 1 LAST TOLERANCE 10%
J 0
(-6950 4125);
DISPLAY 0.617021 (-6950 4125);
PAINT SKYBLUE (-6950 4125);
FORCEPROP 1 LAST VALUE 10UF
J 0
(-6950 4225);
DISPLAY 0.617021 (-6950 4225);
PAINT SKYBLUE (-6950 4225);
FORCEPROP 1 LAST VOLTAGE 16V
J 0
(-6950 4175);
DISPLAY 0.617021 (-6950 4175);
PAINT SKYBLUE (-6950 4175);
FORCEPROP 1 LASTPIN (-7000 4275) $PN 1
J 0
(-6990 4255);
DISPLAY 0.617021 (-6990 4255);
PAINT ORANGE (-6990 4255);
FORCEPROP 1 LAST PART_NUMBER C95333-007
J 0
(-6950 4025);
DISPLAY 0.617021 (-6950 4025);
PAINT BLUE (-6950 4025);
FORCEPROP 1 LAST PACK_TYPE 0805
J 0
(-6950 3975);
DISPLAY 0.617021 (-6950 3975);
PAINT SKYBLUE (-6950 3975);
FORCEPROP 1 LASTPIN (-7000 4075) $PN 2
J 0
(-6990 4055);
DISPLAY 0.617021 (-6990 4055);
PAINT ORANGE (-6990 4055);
FORCEPROP 1 LAST LOCATION C6P19
J 0
(-6950 4275);
DISPLAY 0.617021 (-6950 4275);
PAINT AQUA (-6950 4275);
FORCEPROP 1 LAST MATERIAL X6S
J 0
(-6950 4075);
DISPLAY 0.617021 (-6950 4075);
PAINT SKYBLUE (-6950 4075);
FORCEPROP 1 LAST PATH I54
J 0
(-6950 4325);
DISPLAY 0.978723 (-6950 4325);
PAINT WHITE (-6950 4325);
DISPLAY INVISIBLE (-6950 4325);
FORCEPROP 2 LAST ROOM PVCCIN_CPU0_PWR_VR
J 0
(-6950 4325);
DISPLAY 1.361702 (-6950 4325);
PAINT ORANGE (-6950 4325);
DISPLAY INVISIBLE (-6950 4325);
FORCEPROP 2 LAST CDS_LOCATION C6P19
J 0
(-6950 4275);
DISPLAY 0.617021 (-6950 4275);
PAINT AQUA (-6950 4275);
DISPLAY INVISIBLE (-6950 4275);
FORCEPROP 2 LAST SEC 1
J 0
(-6950 4375);
DISPLAY 0.680851 (-6950 4375);
PAINT MONO (-6950 4375);
DISPLAY INVISIBLE (-6950 4375);
FORCEPROP 2 LAST SEC_TYPE 0805
J 0
(-6950 4375);
DISPLAY 1.021277 (-6950 4375);
PAINT ORANGE (-6950 4375);
DISPLAY INVISIBLE (-6950 4375);
FORCEPROP 2 LAST CDS_LIB mstr_discrete
J 0
(-7000 4175);
PAINT ORANGE (-7000 4175);
DISPLAY INVISIBLE (-7000 4175);
FORCEADD OFFPAGE..1
(-6575 3825);
FORCEPROP 2 LASTPIN (-6525 3825) SIG_NAME VR_PVCCIN_CPU0_PWM3
J 0
(-6510 3835);
DISPLAY 0.617021 (-6510 3835);
PAINT ORANGE (-6510 3835);
FORCEPROP 2 LAST $XR0 201 
J 0
(-6827 3825);
DISPLAY 0.638298 (-6827 3825);
PAINT MONO (-6827 3825);
FORCEPROP 1 LAST COMMENT_BODY TRUE
J 0
(-6450 3725);
DISPLAY 1.680851 (-6450 3725);
PAINT GREEN (-6450 3725);
DISPLAY INVISIBLE (-6450 3725);
FORCEPROP 1 LAST OFFPAGE TRUE
J 0
(-6250 3700);
DISPLAY 1.680851 (-6250 3700);
PAINT GREEN (-6250 3700);
DISPLAY INVISIBLE (-6250 3700);
FORCEPROP 2 LAST PATH I55
J 0
(-6525 3900);
DISPLAY 1.021277 (-6525 3900);
PAINT ORANGE (-6525 3900);
DISPLAY INVISIBLE (-6525 3900);
FORCEPROP 2 LAST CDS_LIB mstr_standard
J 0
(-6575 3825);
DISPLAY 1.936170 (-6575 3825);
PAINT ORANGE (-6575 3825);
DISPLAY INVISIBLE (-6575 3825);
FORCEPROP 2 LAST BOM_COST PROC_VRD_VCCIN_CPU0
J 0
(-6825 3875);
DISPLAY 1.446809 (-6825 3875);
PAINT MONO (-6825 3875);
DISPLAY INVISIBLE (-6825 3875);
FORCEPROP 2 LAST ROOM PVCCIN_CPU0_PWR_VR
J 0
(-6975 3900);
DISPLAY 1.936170 (-6975 3900);
PAINT ORANGE (-6975 3900);
DISPLAY INVISIBLE (-6975 3900);
FORCEADD GND..1
(-7000 3725);
FORCEPROP 3 LASTPIN (-7000 3775) SIG_NAME GND\g
J 0
(-6990 3785);
DISPLAY 0.659574 (-6990 3785);
PAINT MONO (-6990 3785);
DISPLAY INVISIBLE (-6990 3785);
FORCEPROP 1 LAST HDL_POWER GND
J 0
(-7000 3875);
DISPLAY 1.723404 (-7000 3875);
PAINT GREEN (-7000 3875);
DISPLAY INVISIBLE (-7000 3875);
FORCEPROP 1 LAST BODY_TYPE PLUMBING
J 0
(-7045 3682);
DISPLAY 0.340426 (-7045 3682);
PAINT GREEN (-7045 3682);
DISPLAY INVISIBLE (-7045 3682);
FORCEPROP 2 LAST ROOM PVCCIN_CPU0_PWR_VR
J 0
(-7550 3800);
DISPLAY 1.936170 (-7550 3800);
PAINT ORANGE (-7550 3800);
DISPLAY INVISIBLE (-7550 3800);
FORCEPROP 2 LAST BOM_COST PROC_VRD_VCCIN_CPU0
J 0
(-7375 3800);
DISPLAY 1.446809 (-7375 3800);
PAINT MONO (-7375 3800);
DISPLAY INVISIBLE (-7375 3800);
FORCEPROP 1 LAST VOLTAGE 0
J 0
(-7000 3725);
PAINT SKYBLUE (-7000 3725);
DISPLAY INVISIBLE (-7000 3725);
FORCEPROP 2 LAST CDS_LIB mstr_symbols
J 0
(-7000 3725);
DISPLAY 1.936170 (-7000 3725);
PAINT ORANGE (-7000 3725);
DISPLAY INVISIBLE (-7000 3725);
FORCEPROP 1 LAST SIZE 1B
J 0
(-6925 3675);
DISPLAY 1.723404 (-6925 3675);
PAINT GREEN (-6925 3675);
DISPLAY INVISIBLE (-6925 3675);
FORCEPROP 1 LAST PATH I56
J 0
(-6925 3725);
DISPLAY 0.872340 (-6925 3725);
PAINT AQUA (-6925 3725);
DISPLAY INVISIBLE (-6925 3725);
FORCEADD CAP..1
(-6550 1475);
FORCEPROP 1 LAST VOLTAGE 16V
J 0
(-6500 1475);
DISPLAY 0.617021 (-6500 1475);
PAINT SKYBLUE (-6500 1475);
FORCEPROP 1 LASTPIN (-6550 1575) $PN 1
J 0
(-6540 1555);
DISPLAY 0.617021 (-6540 1555);
PAINT ORANGE (-6540 1555);
FORCEPROP 1 LASTPIN (-6550 1375) $PN 2
J 0
(-6540 1355);
DISPLAY 0.617021 (-6540 1355);
PAINT ORANGE (-6540 1355);
FORCEPROP 1 LAST TOLERANCE 10%
J 0
(-6500 1425);
DISPLAY 0.617021 (-6500 1425);
PAINT SKYBLUE (-6500 1425);
FORCEPROP 1 LAST MATERIAL X6S
J 0
(-6500 1375);
DISPLAY 0.617021 (-6500 1375);
PAINT SKYBLUE (-6500 1375);
FORCEPROP 1 LAST LOCATION C6P20
J 0
(-6500 1575);
DISPLAY 0.617021 (-6500 1575);
PAINT AQUA (-6500 1575);
FORCEPROP 1 LAST VALUE 10UF
J 0
(-6500 1525);
DISPLAY 0.617021 (-6500 1525);
PAINT SKYBLUE (-6500 1525);
FORCEPROP 1 LAST PART_NUMBER C95333-007
J 0
(-6500 1325);
DISPLAY 0.617021 (-6500 1325);
PAINT BLUE (-6500 1325);
FORCEPROP 1 LAST PACK_TYPE 0805
J 0
(-6500 1275);
DISPLAY 0.617021 (-6500 1275);
PAINT SKYBLUE (-6500 1275);
FORCEPROP 2 LAST CDS_LIB mstr_discrete
J 0
(-6550 1475);
PAINT ORANGE (-6550 1475);
DISPLAY INVISIBLE (-6550 1475);
FORCEPROP 2 LAST CDS_LOCATION C6P20
J 0
(-6500 1575);
DISPLAY 0.617021 (-6500 1575);
PAINT AQUA (-6500 1575);
DISPLAY INVISIBLE (-6500 1575);
FORCEPROP 2 LAST SEC_TYPE 0805
J 0
(-6500 1675);
DISPLAY 1.021277 (-6500 1675);
PAINT ORANGE (-6500 1675);
DISPLAY INVISIBLE (-6500 1675);
FORCEPROP 2 LAST SEC 1
J 0
(-6500 1675);
DISPLAY 0.680851 (-6500 1675);
PAINT MONO (-6500 1675);
DISPLAY INVISIBLE (-6500 1675);
FORCEPROP 1 LAST PATH I57
J 0
(-6500 1625);
DISPLAY 0.978723 (-6500 1625);
PAINT WHITE (-6500 1625);
DISPLAY INVISIBLE (-6500 1625);
FORCEPROP 2 LAST ROOM PVCCIN_CPU0_PWR_VR
J 0
(-6500 1625);
DISPLAY 1.361702 (-6500 1625);
PAINT ORANGE (-6500 1625);
DISPLAY INVISIBLE (-6500 1625);
FORCEADD CAP..1
(-6825 1475);
FORCEPROP 1 LAST VOLTAGE 16V
J 0
(-6775 1475);
DISPLAY 0.617021 (-6775 1475);
PAINT SKYBLUE (-6775 1475);
FORCEPROP 1 LASTPIN (-6825 1375) $PN 2
J 0
(-6815 1355);
DISPLAY 0.617021 (-6815 1355);
PAINT ORANGE (-6815 1355);
FORCEPROP 1 LASTPIN (-6825 1575) $PN 1
J 0
(-6815 1555);
DISPLAY 0.617021 (-6815 1555);
PAINT ORANGE (-6815 1555);
FORCEPROP 1 LAST PACK_TYPE 0805
J 0
(-6775 1275);
DISPLAY 0.617021 (-6775 1275);
PAINT SKYBLUE (-6775 1275);
FORCEPROP 1 LAST PART_NUMBER C95333-007
J 0
(-6775 1325);
DISPLAY 0.617021 (-6775 1325);
PAINT BLUE (-6775 1325);
FORCEPROP 1 LAST MATERIAL X6S
J 0
(-6775 1375);
DISPLAY 0.617021 (-6775 1375);
PAINT SKYBLUE (-6775 1375);
FORCEPROP 1 LAST TOLERANCE 10%
J 0
(-6775 1425);
DISPLAY 0.617021 (-6775 1425);
PAINT SKYBLUE (-6775 1425);
FORCEPROP 1 LAST VALUE 10UF
J 0
(-6775 1525);
DISPLAY 0.617021 (-6775 1525);
PAINT SKYBLUE (-6775 1525);
FORCEPROP 1 LAST LOCATION C6P15
J 0
(-6775 1575);
DISPLAY 0.617021 (-6775 1575);
PAINT AQUA (-6775 1575);
FORCEPROP 2 LAST ROOM PVCCIN_CPU0_PWR_VR
J 0
(-6775 1625);
DISPLAY 1.361702 (-6775 1625);
PAINT ORANGE (-6775 1625);
DISPLAY INVISIBLE (-6775 1625);
FORCEPROP 1 LAST PATH I58
J 0
(-6775 1625);
DISPLAY 0.978723 (-6775 1625);
PAINT WHITE (-6775 1625);
DISPLAY INVISIBLE (-6775 1625);
FORCEPROP 2 LAST CDS_LOCATION C6P15
J 0
(-6775 1575);
DISPLAY 0.617021 (-6775 1575);
PAINT AQUA (-6775 1575);
DISPLAY INVISIBLE (-6775 1575);
FORCEPROP 2 LAST SEC 1
J 0
(-6775 1675);
DISPLAY 0.680851 (-6775 1675);
PAINT MONO (-6775 1675);
DISPLAY INVISIBLE (-6775 1675);
FORCEPROP 2 LAST SEC_TYPE 0805
J 0
(-6775 1675);
DISPLAY 1.021277 (-6775 1675);
PAINT ORANGE (-6775 1675);
DISPLAY INVISIBLE (-6775 1675);
FORCEPROP 2 LAST CDS_LIB mstr_discrete
J 0
(-6825 1475);
PAINT ORANGE (-6825 1475);
DISPLAY INVISIBLE (-6825 1475);
FORCEADD CAP..1
(-7100 1475);
FORCEPROP 1 LAST LOCATION C6P7
J 0
(-7050 1575);
DISPLAY 0.617021 (-7050 1575);
PAINT AQUA (-7050 1575);
FORCEPROP 1 LAST VOLTAGE 16V
J 0
(-7050 1475);
DISPLAY 0.617021 (-7050 1475);
PAINT SKYBLUE (-7050 1475);
FORCEPROP 1 LAST VALUE 10UF
J 0
(-7050 1525);
DISPLAY 0.617021 (-7050 1525);
PAINT SKYBLUE (-7050 1525);
FORCEPROP 1 LASTPIN (-7100 1575) $PN 1
J 0
(-7090 1555);
DISPLAY 0.617021 (-7090 1555);
PAINT ORANGE (-7090 1555);
FORCEPROP 1 LAST TOLERANCE 10%
J 0
(-7050 1425);
DISPLAY 0.617021 (-7050 1425);
PAINT SKYBLUE (-7050 1425);
FORCEPROP 1 LAST MATERIAL X6S
J 0
(-7050 1375);
DISPLAY 0.617021 (-7050 1375);
PAINT SKYBLUE (-7050 1375);
FORCEPROP 1 LASTPIN (-7100 1375) $PN 2
J 0
(-7090 1355);
DISPLAY 0.617021 (-7090 1355);
PAINT ORANGE (-7090 1355);
FORCEPROP 1 LAST PART_NUMBER C95333-007
J 0
(-7050 1325);
DISPLAY 0.617021 (-7050 1325);
PAINT BLUE (-7050 1325);
FORCEPROP 1 LAST PACK_TYPE 0805
J 0
(-7050 1275);
DISPLAY 0.617021 (-7050 1275);
PAINT SKYBLUE (-7050 1275);
FORCEPROP 2 LAST CDS_LIB mstr_discrete
J 0
(-7100 1475);
PAINT ORANGE (-7100 1475);
DISPLAY INVISIBLE (-7100 1475);
FORCEPROP 2 LAST SEC_TYPE 0805
J 0
(-7050 1675);
DISPLAY 1.021277 (-7050 1675);
PAINT ORANGE (-7050 1675);
DISPLAY INVISIBLE (-7050 1675);
FORCEPROP 2 LAST SEC 1
J 0
(-7050 1675);
DISPLAY 0.680851 (-7050 1675);
PAINT MONO (-7050 1675);
DISPLAY INVISIBLE (-7050 1675);
FORCEPROP 2 LAST CDS_LOCATION C6P7
J 0
(-7050 1575);
DISPLAY 0.617021 (-7050 1575);
PAINT AQUA (-7050 1575);
DISPLAY INVISIBLE (-7050 1575);
FORCEPROP 2 LAST ROOM PVCCIN_CPU0_PWR_VR
J 0
(-7050 1625);
DISPLAY 1.361702 (-7050 1625);
PAINT ORANGE (-7050 1625);
DISPLAY INVISIBLE (-7050 1625);
FORCEPROP 1 LAST PATH I59
J 0
(-7050 1625);
DISPLAY 0.978723 (-7050 1625);
PAINT WHITE (-7050 1625);
DISPLAY INVISIBLE (-7050 1625);
FORCEADD OFFPAGE..2
(-775 4475);
FORCEPROP 2 LAST $XR0 201 
J 0
(-586 4475);
DISPLAY 0.638298 (-586 4475);
PAINT MONO (-586 4475);
FORCEPROP 1 LAST COMMENT_BODY TRUE
J 0
(-820 4380);
DISPLAY 1.723404 (-820 4380);
PAINT GREEN (-820 4380);
DISPLAY INVISIBLE (-820 4380);
FORCEPROP 1 LAST OFFPAGE TRUE
J 0
(-450 4350);
DISPLAY 1.723404 (-450 4350);
PAINT GREEN (-450 4350);
DISPLAY INVISIBLE (-450 4350);
FORCEPROP 2 LAST BOM_COST PROC_VRD_VCCIN_CPU0
J 0
(-575 4525);
DISPLAY 1.446809 (-575 4525);
PAINT MONO (-575 4525);
DISPLAY INVISIBLE (-575 4525);
FORCEPROP 2 LAST PATH I6
J 0
(-600 4550);
DISPLAY 1.021277 (-600 4550);
PAINT ORANGE (-600 4550);
DISPLAY INVISIBLE (-600 4550);
FORCEPROP 2 LAST CDS_LIB mstr_standard
J 0
(-775 4475);
DISPLAY 1.936170 (-775 4475);
PAINT ORANGE (-775 4475);
DISPLAY INVISIBLE (-775 4475);
FORCEPROP 2 LAST ROOM PVCCIN_CPU0_PWR_VR
J 0
(-1175 4550);
DISPLAY 1.936170 (-1175 4550);
PAINT ORANGE (-1175 4550);
DISPLAY INVISIBLE (-1175 4550);
FORCEADD OFFPAGE..1
(-6550 1100);
FORCEPROP 2 LAST $XR0 201 
J 0
(-6802 1100);
DISPLAY 0.638298 (-6802 1100);
PAINT MONO (-6802 1100);
FORCEPROP 1 LAST COMMENT_BODY TRUE
J 0
(-6425 1000);
DISPLAY 1.680851 (-6425 1000);
PAINT GREEN (-6425 1000);
DISPLAY INVISIBLE (-6425 1000);
FORCEPROP 1 LAST OFFPAGE TRUE
J 0
(-6225 975);
DISPLAY 1.680851 (-6225 975);
PAINT GREEN (-6225 975);
DISPLAY INVISIBLE (-6225 975);
FORCEPROP 2 LAST PATH I60
J 0
(-6500 1175);
DISPLAY 1.021277 (-6500 1175);
PAINT ORANGE (-6500 1175);
DISPLAY INVISIBLE (-6500 1175);
FORCEPROP 2 LAST CDS_LIB mstr_standard
J 0
(-6550 1100);
PAINT ORANGE (-6550 1100);
DISPLAY INVISIBLE (-6550 1100);
FORCEPROP 2 LAST BOM_COST PROC_VRD_VCCIN_CPU0
J 0
(-6800 1150);
DISPLAY 1.446809 (-6800 1150);
PAINT MONO (-6800 1150);
DISPLAY INVISIBLE (-6800 1150);
FORCEPROP 2 LAST ROOM PVCCIN_CPU0_PWR_VR
J 0
(-6950 1175);
DISPLAY 1.936170 (-6950 1175);
PAINT ORANGE (-6950 1175);
DISPLAY INVISIBLE (-6950 1175);
FORCEADD VCC_CORE..1
(-6650 1900);
FORCEPROP 3 LASTPIN (-6650 1850) SIG_NAME VR_FET_SW_P12V_STBY_PVCCIN_CPU0\g
J 0
(-6640 1860);
DISPLAY 0.659574 (-6640 1860);
PAINT MONO (-6640 1860);
DISPLAY INVISIBLE (-6640 1860);
FORCEPROP 1 LAST HDL_POWER VR_FET_SW_P12V_STBY_PVCCIN_CPU0
J 1
(-6625 1950);
DISPLAY 0.617021 (-6625 1950);
PAINT GREEN (-6625 1950);
FORCEPROP 1 LAST PATH I61
J 0
(-6600 1925);
DISPLAY 0.872340 (-6600 1925);
PAINT AQUA (-6600 1925);
DISPLAY INVISIBLE (-6600 1925);
FORCEPROP 2 LAST CDS_LIB mstr_symbols
J 0
(-6650 1900);
PAINT ORANGE (-6650 1900);
DISPLAY INVISIBLE (-6650 1900);
FORCEADD GND..1
(-7100 1000);
FORCEPROP 3 LASTPIN (-7100 1050) SIG_NAME GND\g
J 0
(-7090 1060);
DISPLAY 0.659574 (-7090 1060);
PAINT MONO (-7090 1060);
DISPLAY INVISIBLE (-7090 1060);
FORCEPROP 1 LAST HDL_POWER GND
J 0
(-7100 1150);
DISPLAY 1.723404 (-7100 1150);
PAINT GREEN (-7100 1150);
DISPLAY INVISIBLE (-7100 1150);
FORCEPROP 1 LAST BODY_TYPE PLUMBING
J 0
(-7145 957);
DISPLAY 0.340426 (-7145 957);
PAINT GREEN (-7145 957);
DISPLAY INVISIBLE (-7145 957);
FORCEPROP 1 LAST SIZE 1B
J 0
(-7025 950);
DISPLAY 1.723404 (-7025 950);
PAINT GREEN (-7025 950);
DISPLAY INVISIBLE (-7025 950);
FORCEPROP 2 LAST ROOM PVCCIN_CPU0_PWR_VR
J 0
(-7650 1075);
DISPLAY 1.936170 (-7650 1075);
PAINT ORANGE (-7650 1075);
DISPLAY INVISIBLE (-7650 1075);
FORCEPROP 2 LAST BOM_COST PROC_VRD_VCCIN_CPU0
J 0
(-7475 1075);
DISPLAY 1.446809 (-7475 1075);
PAINT MONO (-7475 1075);
DISPLAY INVISIBLE (-7475 1075);
FORCEPROP 2 LAST CDS_LIB mstr_symbols
J 0
(-7100 1000);
PAINT ORANGE (-7100 1000);
DISPLAY INVISIBLE (-7100 1000);
FORCEPROP 1 LAST VOLTAGE 0
J 0
(-7100 1000);
PAINT SKYBLUE (-7100 1000);
DISPLAY INVISIBLE (-7100 1000);
FORCEPROP 1 LAST PATH I62
J 0
(-7025 1000);
DISPLAY 0.872340 (-7025 1000);
PAINT AQUA (-7025 1000);
DISPLAY INVISIBLE (-7025 1000);
FORCEADD GND..1
(-2550 525);
FORCEPROP 3 LASTPIN (-2550 575) SIG_NAME GND\g
J 0
(-2540 585);
DISPLAY 0.659574 (-2540 585);
PAINT MONO (-2540 585);
DISPLAY INVISIBLE (-2540 585);
FORCEPROP 1 LAST HDL_POWER GND
J 0
(-2550 675);
DISPLAY 1.723404 (-2550 675);
PAINT GREEN (-2550 675);
DISPLAY INVISIBLE (-2550 675);
FORCEPROP 1 LAST BODY_TYPE PLUMBING
J 0
(-2595 482);
DISPLAY 0.340426 (-2595 482);
PAINT GREEN (-2595 482);
DISPLAY INVISIBLE (-2595 482);
FORCEPROP 1 LAST VOLTAGE 0
J 0
(-2550 525);
PAINT SKYBLUE (-2550 525);
DISPLAY INVISIBLE (-2550 525);
FORCEPROP 2 LAST CDS_LIB mstr_symbols
J 0
(-2550 525);
PAINT ORANGE (-2550 525);
DISPLAY INVISIBLE (-2550 525);
FORCEPROP 1 LAST SIZE 1B
J 0
(-2475 475);
DISPLAY 1.723404 (-2475 475);
PAINT GREEN (-2475 475);
DISPLAY INVISIBLE (-2475 475);
FORCEPROP 1 LAST PATH I63
J 0
(-2475 525);
DISPLAY 0.872340 (-2475 525);
PAINT AQUA (-2475 525);
DISPLAY INVISIBLE (-2475 525);
FORCEPROP 2 LAST BOM_COST PROC_VRD_VCCIN_CPU0
J 0
(-2925 600);
DISPLAY 1.446809 (-2925 600);
PAINT MONO (-2925 600);
DISPLAY INVISIBLE (-2925 600);
FORCEPROP 2 LAST ROOM PVCCIN_CPU0_PWR_VR
J 0
(-3100 600);
DISPLAY 1.936170 (-3100 600);
PAINT ORANGE (-3100 600);
DISPLAY INVISIBLE (-3100 600);
FORCEADD P5V_STBY..1
(-4400 4875);
FORCEPROP 3 LASTPIN (-4400 4825) SIG_NAME P5V_STBY\g
J 0
(-4390 4835);
DISPLAY 0.659574 (-4390 4835);
PAINT MONO (-4390 4835);
DISPLAY INVISIBLE (-4390 4835);
FORCEPROP 1 LAST HDL_POWER P5V_STBY
J 0
(-4700 4750);
DISPLAY 0.872340 (-4700 4750);
PAINT ORANGE (-4700 4750);
DISPLAY INVISIBLE (-4700 4750);
FORCEPROP 1 LAST BODY_TYPE PLUMBING
J 0
(-4445 4832);
DISPLAY 0.340426 (-4445 4832);
PAINT GREEN (-4445 4832);
DISPLAY INVISIBLE (-4445 4832);
FORCEPROP 1 LAST SIZE 1B
J 0
(-4355 4897);
DISPLAY 0.340426 (-4355 4897);
PAINT GREEN (-4355 4897);
DISPLAY INVISIBLE (-4355 4897);
FORCEPROP 1 LAST PATH I64
J 0
(-4355 4877);
DISPLAY 0.340426 (-4355 4877);
PAINT GREEN (-4355 4877);
DISPLAY INVISIBLE (-4355 4877);
FORCEPROP 2 LAST CDS_LIB mstr_symbols
J 0
(-4400 4875);
PAINT ORANGE (-4400 4875);
DISPLAY INVISIBLE (-4400 4875);
FORCEPROP 1 LAST VOLTAGE 5.0V
J 0
(-4445 4832);
DISPLAY 0.340426 (-4445 4832);
PAINT SKYBLUE (-4445 4832);
DISPLAY INVISIBLE (-4445 4832);
FORCEADD P5V_STBY..1
(-4375 2125);
FORCEPROP 3 LASTPIN (-4375 2075) SIG_NAME P5V_STBY\g
J 0
(-4365 2085);
DISPLAY 0.659574 (-4365 2085);
PAINT MONO (-4365 2085);
DISPLAY INVISIBLE (-4365 2085);
FORCEPROP 1 LAST HDL_POWER P5V_STBY
J 0
(-4675 2000);
DISPLAY 0.872340 (-4675 2000);
PAINT ORANGE (-4675 2000);
DISPLAY INVISIBLE (-4675 2000);
FORCEPROP 1 LAST BODY_TYPE PLUMBING
J 0
(-4420 2082);
DISPLAY 0.340426 (-4420 2082);
PAINT GREEN (-4420 2082);
DISPLAY INVISIBLE (-4420 2082);
FORCEPROP 1 LAST VOLTAGE 5.0V
J 0
(-4420 2082);
DISPLAY 0.340426 (-4420 2082);
PAINT SKYBLUE (-4420 2082);
DISPLAY INVISIBLE (-4420 2082);
FORCEPROP 2 LAST CDS_LIB mstr_symbols
J 0
(-4375 2125);
PAINT ORANGE (-4375 2125);
DISPLAY INVISIBLE (-4375 2125);
FORCEPROP 1 LAST SIZE 1B
J 0
(-4330 2147);
DISPLAY 0.340426 (-4330 2147);
PAINT GREEN (-4330 2147);
DISPLAY INVISIBLE (-4330 2147);
FORCEPROP 1 LAST PATH I65
J 0
(-4330 2127);
DISPLAY 0.340426 (-4330 2127);
PAINT GREEN (-4330 2127);
DISPLAY INVISIBLE (-4330 2127);
FORCEADD CAP_A..1
(-800 3450);
FORCEPROP 1 LAST TOLERANCE 20%
J 0
(-750 3450);
DISPLAY 0.617021 (-750 3450);
PAINT SKYBLUE (-750 3450);
FORCEPROP 1 LAST VOLTAGE 4V
J 0
(-750 3500);
DISPLAY 0.617021 (-750 3500);
PAINT SKYBLUE (-750 3500);
FORCEPROP 1 LAST VALUE 22.0UF
J 0
(-750 3550);
DISPLAY 0.617021 (-750 3550);
PAINT SKYBLUE (-750 3550);
FORCEPROP 1 LAST LOCATION C6P21
J 0
(-750 3600);
DISPLAY 0.617021 (-750 3600);
PAINT AQUA (-750 3600);
FORCEPROP 1 LASTPIN (-800 3550) $PN 1
J 0
(-790 3530);
DISPLAY 0.617021 (-790 3530);
PAINT ORANGE (-790 3530);
FORCEPROP 1 LASTPIN (-800 3350) $PN 2
J 0
(-790 3330);
DISPLAY 0.617021 (-790 3330);
PAINT ORANGE (-790 3330);
FORCEPROP 1 LAST PACK_TYPE 0603V
J 0
(-750 3300);
DISPLAY 0.617021 (-750 3300);
PAINT SKYBLUE (-750 3300);
FORCEPROP 1 LAST MATERIAL X6S
J 0
(-750 3400);
DISPLAY 0.617021 (-750 3400);
PAINT SKYBLUE (-750 3400);
FORCEPROP 0 LAST GROUP PWR_MLCC_CAP
J 0
(-750 3250);
DISPLAY 0.638298 (-750 3250);
PAINT BROWN (-750 3250);
DISPLAY BOTH (-750 3250);
FORCEPROP 1 LAST PART_NUMBER E15431-004
J 0
(-750 3350);
DISPLAY 0.617021 (-750 3350);
PAINT BLUE (-750 3350);
FORCEPROP 2 LAST CDS_LIB dev_discrete
J 0
(-800 3450);
PAINT ORANGE (-800 3450);
DISPLAY INVISIBLE (-800 3450);
FORCEPROP 1 LAST PATH I66
J 0
(-750 3600);
DISPLAY 0.978723 (-750 3600);
PAINT WHITE (-750 3600);
DISPLAY INVISIBLE (-750 3600);
FORCEPROP 2 LAST CDS_SEC 1
J 0
(-750 3600);
PAINT ORANGE (-750 3600);
DISPLAY INVISIBLE (-750 3600);
FORCEPROP 2 LAST CDS_LOCATION C6P21
J 0
(-750 3550);
DISPLAY 0.617021 (-750 3550);
PAINT AQUA (-750 3550);
DISPLAY INVISIBLE (-750 3550);
FORCEPROP 0 LAST ROOM PVCCIN_CPU0_PWR_VR
J 0
(-750 3650);
DISPLAY 1.021277 (-750 3650);
PAINT ORANGE (-750 3650);
DISPLAY INVISIBLE (-750 3650);
FORCEPROP 2 LAST SEC 1
J 0
(-750 3650);
DISPLAY 0.680851 (-750 3650);
PAINT MONO (-750 3650);
DISPLAY INVISIBLE (-750 3650);
FORCEPROP 2 LAST SEC_TYPE 0603V
J 0
(-750 3650);
DISPLAY 1.021277 (-750 3650);
PAINT ORANGE (-750 3650);
DISPLAY INVISIBLE (-750 3650);
FORCEPROP 0 LAST BOM_COST PROC_VRD_VCCIN_CPU0
J 0
(-750 3650);
DISPLAY 1.021277 (-750 3650);
PAINT ORANGE (-750 3650);
DISPLAY INVISIBLE (-750 3650);
FORCEADD RES..2
(-475 2550);
FORCEPROP 1 LASTPIN (-475 2450) $PN 2
J 0
(-470 2460);
DISPLAY 0.617021 (-470 2460);
PAINT ORANGE (-470 2460);
FORCEPROP 1 LASTPIN (-475 2650) $PN 1
J 0
(-470 2612);
DISPLAY 0.617021 (-470 2612);
PAINT ORANGE (-470 2612);
FORCEPROP 1 LAST PACK_TYPE 0603
J 0
(-435 2375);
DISPLAY 0.617021 (-435 2375);
PAINT SKYBLUE (-435 2375);
FORCEPROP 1 LAST PART_NUMBER G22026-038
J 0
(-435 2425);
DISPLAY 0.617021 (-435 2425);
PAINT BLUE (-435 2425);
FORCEPROP 1 LAST MATERIAL CHIP
J 0
(-435 2475);
DISPLAY 0.617021 (-435 2475);
PAINT SKYBLUE (-435 2475);
FORCEPROP 1 LAST WATTAGE 1/10W
J 0
(-435 2525);
DISPLAY 0.617021 (-435 2525);
PAINT SKYBLUE (-435 2525);
FORCEPROP 1 LAST TOLERANCE 1%
J 0
(-430 2575);
DISPLAY 0.617021 (-430 2575);
PAINT SKYBLUE (-430 2575);
FORCEPROP 1 LAST VALUE 100.0
J 0
(-430 2625);
DISPLAY 0.617021 (-430 2625);
PAINT SKYBLUE (-430 2625);
FORCEPROP 1 LAST LOCATION R4E13
J 0
(-430 2675);
DISPLAY 0.617021 (-430 2675);
PAINT AQUA (-430 2675);
FORCEPROP 2 LAST SEC_TYPE 0603
J 0
(-425 2775);
DISPLAY 1.021277 (-425 2775);
PAINT ORANGE (-425 2775);
DISPLAY INVISIBLE (-425 2775);
FORCEPROP 0 LAST BOM_COST PROC_VRD_VCCIN_CPU0
J 0
(-425 2775);
DISPLAY 1.021277 (-425 2775);
PAINT ORANGE (-425 2775);
DISPLAY INVISIBLE (-425 2775);
FORCEPROP 2 LAST SEC 1
J 0
(-425 2775);
DISPLAY 0.680851 (-425 2775);
PAINT MONO (-425 2775);
DISPLAY INVISIBLE (-425 2775);
FORCEPROP 2 LAST CDS_LOCATION R4E13
J 0
(-430 2675);
DISPLAY 0.617021 (-430 2675);
PAINT AQUA (-430 2675);
DISPLAY INVISIBLE (-430 2675);
FORCEPROP 1 LAST PATH I67
J 0
(-425 2725);
DISPLAY 0.978723 (-425 2725);
PAINT WHITE (-425 2725);
DISPLAY INVISIBLE (-425 2725);
FORCEPROP 0 LAST ROOM PVCCIN_CPU0_DECAP_VR
J 0
(-425 2775);
DISPLAY 1.021277 (-425 2775);
PAINT ORANGE (-425 2775);
DISPLAY INVISIBLE (-425 2775);
FORCEPROP 2 LAST CDS_LIB mstr_discrete
J 0
(-475 2550);
PAINT ORANGE (-475 2550);
DISPLAY INVISIBLE (-475 2550);
FORCEADD CAP_A..1
(-500 3450);
FORCEPROP 1 LAST VALUE 22.0UF
J 0
(-450 3550);
DISPLAY 0.617021 (-450 3550);
PAINT SKYBLUE (-450 3550);
FORCEPROP 1 LAST VOLTAGE 4V
J 0
(-450 3500);
DISPLAY 0.617021 (-450 3500);
PAINT SKYBLUE (-450 3500);
FORCEPROP 1 LASTPIN (-500 3350) $PN 2
J 0
(-490 3330);
DISPLAY 0.617021 (-490 3330);
PAINT ORANGE (-490 3330);
FORCEPROP 1 LAST TOLERANCE 20%
J 0
(-450 3450);
DISPLAY 0.617021 (-450 3450);
PAINT SKYBLUE (-450 3450);
FORCEPROP 1 LAST LOCATION C4D34
J 0
(-450 3600);
DISPLAY 0.617021 (-450 3600);
PAINT AQUA (-450 3600);
FORCEPROP 1 LASTPIN (-500 3550) $PN 1
J 0
(-490 3530);
DISPLAY 0.617021 (-490 3530);
PAINT ORANGE (-490 3530);
FORCEPROP 1 LAST MATERIAL X6S
J 0
(-450 3400);
DISPLAY 0.617021 (-450 3400);
PAINT SKYBLUE (-450 3400);
FORCEPROP 1 LAST PACK_TYPE 0603V
J 0
(-450 3300);
DISPLAY 0.617021 (-450 3300);
PAINT SKYBLUE (-450 3300);
FORCEPROP 0 LAST GROUP PWR_MLCC_CAP
J 0
(-450 3200);
DISPLAY 0.638298 (-450 3200);
PAINT BROWN (-450 3200);
DISPLAY BOTH (-450 3200);
FORCEPROP 1 LAST PART_NUMBER E15431-004
J 0
(-450 3350);
DISPLAY 0.617021 (-450 3350);
PAINT BLUE (-450 3350);
FORCEPROP 2 LAST SEC_TYPE 0603V
J 0
(-450 3650);
DISPLAY 1.021277 (-450 3650);
PAINT ORANGE (-450 3650);
DISPLAY INVISIBLE (-450 3650);
FORCEPROP 2 LAST SEC 1
J 0
(-450 3650);
DISPLAY 0.680851 (-450 3650);
PAINT MONO (-450 3650);
DISPLAY INVISIBLE (-450 3650);
FORCEPROP 2 LAST CDS_LOCATION C4D34
J 0
(-450 3550);
DISPLAY 0.617021 (-450 3550);
PAINT AQUA (-450 3550);
DISPLAY INVISIBLE (-450 3550);
FORCEPROP 2 LAST CDS_LIB dev_discrete
J 0
(-500 3450);
PAINT ORANGE (-500 3450);
DISPLAY INVISIBLE (-500 3450);
FORCEPROP 2 LAST CDS_SEC 1
J 0
(-450 3600);
PAINT ORANGE (-450 3600);
DISPLAY INVISIBLE (-450 3600);
FORCEPROP 1 LAST PATH I68
J 0
(-450 3600);
DISPLAY 0.978723 (-450 3600);
PAINT WHITE (-450 3600);
DISPLAY INVISIBLE (-450 3600);
FORCEADD CAP_A..1
(-450 725);
FORCEPROP 1 LASTPIN (-450 825) $PN 1
J 0
(-440 805);
DISPLAY 0.617021 (-440 805);
PAINT ORANGE (-440 805);
FORCEPROP 1 LAST MATERIAL X6S
J 0
(-400 675);
DISPLAY 0.617021 (-400 675);
PAINT SKYBLUE (-400 675);
FORCEPROP 1 LAST LOCATION C4D4
J 0
(-400 875);
DISPLAY 0.617021 (-400 875);
PAINT AQUA (-400 875);
FORCEPROP 1 LAST VOLTAGE 4V
J 0
(-400 775);
DISPLAY 0.617021 (-400 775);
PAINT SKYBLUE (-400 775);
FORCEPROP 1 LAST TOLERANCE 20%
J 0
(-400 725);
DISPLAY 0.617021 (-400 725);
PAINT SKYBLUE (-400 725);
FORCEPROP 1 LAST VALUE 22.0UF
J 0
(-400 825);
DISPLAY 0.617021 (-400 825);
PAINT SKYBLUE (-400 825);
FORCEPROP 1 LASTPIN (-450 625) $PN 2
J 0
(-440 605);
DISPLAY 0.617021 (-440 605);
PAINT ORANGE (-440 605);
FORCEPROP 1 LAST PACK_TYPE 0603V
J 0
(-400 575);
DISPLAY 0.617021 (-400 575);
PAINT SKYBLUE (-400 575);
FORCEPROP 1 LAST PART_NUMBER E15431-004
J 0
(-400 625);
DISPLAY 0.617021 (-400 625);
PAINT BLUE (-400 625);
FORCEPROP 0 LAST GROUP PWR_MLCC_CAP
J 0
(-400 475);
DISPLAY 0.638298 (-400 475);
PAINT BROWN (-400 475);
DISPLAY BOTH (-400 475);
FORCEPROP 2 LAST SEC 1
J 0
(-400 925);
DISPLAY 0.680851 (-400 925);
PAINT MONO (-400 925);
DISPLAY INVISIBLE (-400 925);
FORCEPROP 2 LAST SEC_TYPE 0603V
J 0
(-400 925);
DISPLAY 1.021277 (-400 925);
PAINT ORANGE (-400 925);
DISPLAY INVISIBLE (-400 925);
FORCEPROP 1 LAST PATH I69
J 0
(-400 875);
DISPLAY 0.978723 (-400 875);
PAINT WHITE (-400 875);
DISPLAY INVISIBLE (-400 875);
FORCEPROP 2 LAST CDS_LOCATION C4D4
J 0
(-400 825);
DISPLAY 0.617021 (-400 825);
PAINT AQUA (-400 825);
DISPLAY INVISIBLE (-400 825);
FORCEPROP 2 LAST CDS_LIB dev_discrete
J 0
(-450 725);
PAINT ORANGE (-450 725);
DISPLAY INVISIBLE (-450 725);
FORCEPROP 2 LAST CDS_SEC 1
J 0
(-400 875);
PAINT ORANGE (-400 875);
DISPLAY INVISIBLE (-400 875);
FORCEADD OFFPAGE..2
(-1475 4100);
FORCEPROP 2 LAST $XR3 201 
J 0
(-926 4100);
DISPLAY 0.638298 (-926 4100);
PAINT MONO (-926 4100);
FORCEPROP 2 LAST $XR2 204 
J 0
(-1046 4100);
DISPLAY 0.638298 (-1046 4100);
PAINT MONO (-1046 4100);
FORCEPROP 2 LAST $XR1 203 
J 0
(-1166 4100);
DISPLAY 0.638298 (-1166 4100);
PAINT MONO (-1166 4100);
FORCEPROP 2 LAST $XR0 202 
J 0
(-1286 4100);
DISPLAY 0.638298 (-1286 4100);
PAINT MONO (-1286 4100);
FORCEPROP 1 LAST COMMENT_BODY TRUE
J 0
(-1520 4005);
DISPLAY 1.723404 (-1520 4005);
PAINT GREEN (-1520 4005);
DISPLAY INVISIBLE (-1520 4005);
FORCEPROP 1 LAST OFFPAGE TRUE
J 0
(-1150 3975);
DISPLAY 1.723404 (-1150 3975);
PAINT GREEN (-1150 3975);
DISPLAY INVISIBLE (-1150 3975);
FORCEPROP 2 LAST CDS_LIB mstr_standard
J 0
(-1475 4100);
PAINT ORANGE (-1475 4100);
DISPLAY INVISIBLE (-1475 4100);
FORCEPROP 2 LAST PATH I7
J 0
(-1300 4175);
DISPLAY 1.021277 (-1300 4175);
PAINT ORANGE (-1300 4175);
DISPLAY INVISIBLE (-1300 4175);
FORCEPROP 2 LAST BOM_COST PROC_VRD_VCCIN_CPU0
J 0
(-1275 4150);
DISPLAY 1.446809 (-1275 4150);
PAINT MONO (-1275 4150);
DISPLAY INVISIBLE (-1275 4150);
FORCEPROP 2 LAST ROOM PVCCIN_CPU0_PWR_VR
J 0
(-1875 4175);
DISPLAY 1.936170 (-1875 4175);
PAINT ORANGE (-1875 4175);
DISPLAY INVISIBLE (-1875 4175);
FORCEADD IR354XX..1
(-3100 3925);
FORCEPROP 2 LASTPIN (-3600 3825) $PN 34
J 2
(-3610 3835);
DISPLAY 0.617021 (-3610 3835);
PAINT MONO (-3610 3835);
FORCEPROP 2 LASTPIN (-2600 3625) $PN 10
J 0
(-2590 3635);
DISPLAY 0.617021 (-2590 3635);
PAINT MONO (-2590 3635);
FORCEPROP 2 LASTPIN (-3600 3625) $PN 33
J 2
(-3610 3635);
DISPLAY 0.617021 (-3610 3635);
PAINT MONO (-3610 3635);
FORCEPROP 2 LASTPIN (-3600 4375) $PN 25
J 2
(-3610 4385);
DISPLAY 0.617021 (-3610 4385);
PAINT MONO (-3610 4385);
FORCEPROP 2 LASTPIN (-2600 4275) $PN 37
J 0
(-2590 4285);
DISPLAY 0.617021 (-2590 4285);
PAINT MONO (-2590 4285);
FORCEPROP 1 LAST LOCATION EU4D3
J 0
(-3550 4725);
DISPLAY 0.617021 (-3550 4725);
PAINT AQUA (-3550 4725);
FORCEPROP 1 LAST MATERIAL IC
J 0
(-3550 4675);
DISPLAY 0.617021 (-3550 4675);
PAINT SKYBLUE (-3550 4675);
FORCEPROP 2 LASTPIN (-3600 4425) $PN 30
J 2
(-3610 4435);
DISPLAY 0.617021 (-3610 4435);
PAINT MONO (-3610 4435);
FORCEPROP 2 LASTPIN (-3600 4275) $PN 4
J 2
(-3610 4285);
DISPLAY 0.617021 (-3610 4285);
PAINT MONO (-3610 4285);
FORCEPROP 2 LASTPIN (-3600 4475) $PN 3
J 2
(-3610 4485);
DISPLAY 0.617021 (-3610 4485);
PAINT MONO (-3610 4485);
FORCEPROP 2 LASTPIN (-3600 4175) $PN 35
J 2
(-3610 4185);
DISPLAY 0.617021 (-3610 4185);
PAINT MONO (-3610 4185);
FORCEPROP 2 LASTPIN (-2600 3525) $PN 2
J 0
(-2590 3535);
DISPLAY 0.617021 (-2590 3535);
PAINT MONO (-2590 3535);
FORCEPROP 2 LASTPIN (-2600 3475) $PN 40
J 0
(-2590 3485);
DISPLAY 0.617021 (-2590 3485);
PAINT MONO (-2590 3485);
FORCEPROP 2 LASTPIN (-2600 3425) $PN 7
J 0
(-2590 3435);
DISPLAY 0.617021 (-2590 3435);
PAINT MONO (-2590 3435);
FORCEPROP 2 LASTPIN (-2600 3375) $PN 5
J 0
(-2590 3385);
DISPLAY 0.617021 (-2590 3385);
PAINT MONO (-2590 3385);
FORCEPROP 2 LASTPIN (-3600 3975) $PN 41
J 2
(-3610 3985);
DISPLAY 0.617021 (-3610 3985);
PAINT MONO (-3610 3985);
FORCEPROP 2 LASTPIN (-3600 4075) $PN 1
J 2
(-3610 4085);
DISPLAY 0.617021 (-3610 4085);
PAINT MONO (-3610 4085);
FORCEPROP 2 LASTPIN (-3600 3925) $PN 6
J 2
(-3610 3935);
DISPLAY 0.617021 (-3610 3935);
PAINT MONO (-3610 3935);
FORCEPROP 2 LASTPIN (-3600 3725) $PN 39
J 2
(-3610 3735);
DISPLAY 0.617021 (-3610 3735);
PAINT MONO (-3610 3735);
FORCEPROP 2 LASTPIN (-2600 4225) $PN 31
J 0
(-2590 4235);
DISPLAY 0.617021 (-2590 4235);
PAINT MONO (-2590 4235);
FORCEPROP 2 LASTPIN (-2600 3975) $PN 36
J 0
(-2590 3985);
DISPLAY 0.617021 (-2590 3985);
PAINT MONO (-2590 3985);
FORCEPROP 2 LASTPIN (-3600 3575) $PN 32
J 2
(-3610 3585);
DISPLAY 0.617021 (-3610 3585);
PAINT MONO (-3610 3585);
FORCEPROP 1 LAST PART_NUMBER H73688-001
J 0
(-3550 3225);
DISPLAY 0.617021 (-3550 3225);
PAINT BLUE (-3550 3225);
FORCEPROP 2 LASTPIN (-2600 4475) $PN 38
J 0
(-2590 4485);
DISPLAY 0.617021 (-2590 4485);
PAINT MONO (-2590 4485);
FORCEPROP 1 LAST PATH I70
J 0
(-3100 4675);
PAINT GREEN (-3100 4675);
DISPLAY INVISIBLE (-3100 4675);
FORCEPROP 1 LAST PACK_TYPE SM
J 0
(-3550 4775);
PAINT SKYBLUE (-3550 4775);
DISPLAY INVISIBLE (-3550 4775);
FORCEPROP 2 LAST SEC_TYPE SM
J 0
(-3550 4775);
DISPLAY 1.021277 (-3550 4775);
PAINT ORANGE (-3550 4775);
DISPLAY INVISIBLE (-3550 4775);
FORCEPROP 2 LAST SEC 1
J 0
(-3550 4775);
PAINT MONO (-3550 4775);
DISPLAY INVISIBLE (-3550 4775);
FORCEPROP 2 LAST CDS_LOCATION EU4D3
J 0
(-3550 4725);
PAINT GREEN (-3550 4725);
DISPLAY INVISIBLE (-3550 4725);
FORCEPROP 2 LAST CDS_LIB mstr_discrete
J 0
(-3100 3925);
PAINT ORANGE (-3100 3925);
DISPLAY INVISIBLE (-3100 3925);
FORCEPROP 1 LAST VALUE IR35411
J 1
(-3100 4550);
DISPLAY 0.617021 (-3100 4550);
PAINT SKYBLUE (-3100 4550);
DISPLAY INVISIBLE (-3100 4550);
FORCEADD IR354XX..1
(-3125 1200);
FORCEPROP 2 LASTPIN (-3625 1550) $PN 4
J 2
(-3635 1560);
DISPLAY 0.617021 (-3635 1560);
PAINT MONO (-3635 1560);
FORCEPROP 2 LASTPIN (-2625 800) $PN 2
J 0
(-2615 810);
DISPLAY 0.617021 (-2615 810);
PAINT MONO (-2615 810);
FORCEPROP 2 LASTPIN (-3625 1200) $PN 6
J 2
(-3635 1210);
DISPLAY 0.617021 (-3635 1210);
PAINT MONO (-3635 1210);
FORCEPROP 2 LASTPIN (-3625 1450) $PN 35
J 2
(-3635 1460);
DISPLAY 0.617021 (-3635 1460);
PAINT MONO (-3635 1460);
FORCEPROP 2 LASTPIN (-3625 1700) $PN 30
J 2
(-3635 1710);
DISPLAY 0.617021 (-3635 1710);
PAINT MONO (-3635 1710);
FORCEPROP 2 LASTPIN (-3625 1650) $PN 25
J 2
(-3635 1660);
DISPLAY 0.617021 (-3635 1660);
PAINT MONO (-3635 1660);
FORCEPROP 2 LASTPIN (-3625 1750) $PN 3
J 2
(-3635 1760);
DISPLAY 0.617021 (-3635 1760);
PAINT MONO (-3635 1760);
FORCEPROP 2 LASTPIN (-2625 750) $PN 40
J 0
(-2615 760);
DISPLAY 0.617021 (-2615 760);
PAINT MONO (-2615 760);
FORCEPROP 2 LASTPIN (-2625 900) $PN 10
J 0
(-2615 910);
DISPLAY 0.617021 (-2615 910);
PAINT MONO (-2615 910);
FORCEPROP 2 LASTPIN (-3625 1350) $PN 1
J 2
(-3635 1360);
DISPLAY 0.617021 (-3635 1360);
PAINT MONO (-3635 1360);
FORCEPROP 2 LASTPIN (-3625 1250) $PN 41
J 2
(-3635 1260);
DISPLAY 0.617021 (-3635 1260);
PAINT MONO (-3635 1260);
FORCEPROP 2 LASTPIN (-2625 650) $PN 5
J 0
(-2615 660);
DISPLAY 0.617021 (-2615 660);
PAINT MONO (-2615 660);
FORCEPROP 2 LASTPIN (-2625 1500) $PN 31
J 0
(-2615 1510);
DISPLAY 0.617021 (-2615 1510);
PAINT MONO (-2615 1510);
FORCEPROP 2 LASTPIN (-2625 1550) $PN 37
J 0
(-2615 1560);
DISPLAY 0.617021 (-2615 1560);
PAINT MONO (-2615 1560);
FORCEPROP 2 LASTPIN (-3625 1000) $PN 39
J 2
(-3635 1010);
DISPLAY 0.617021 (-3635 1010);
PAINT MONO (-3635 1010);
FORCEPROP 1 LAST PART_NUMBER H73688-001
J 0
(-3550 500);
DISPLAY 0.617021 (-3550 500);
PAINT BLUE (-3550 500);
FORCEPROP 2 LASTPIN (-3625 850) $PN 32
J 2
(-3635 860);
DISPLAY 0.617021 (-3635 860);
PAINT MONO (-3635 860);
FORCEPROP 2 LASTPIN (-2625 1250) $PN 36
J 0
(-2615 1260);
DISPLAY 0.617021 (-2615 1260);
PAINT MONO (-2615 1260);
FORCEPROP 2 LASTPIN (-2625 700) $PN 7
J 0
(-2615 710);
DISPLAY 0.617021 (-2615 710);
PAINT MONO (-2615 710);
FORCEPROP 2 LASTPIN (-3625 900) $PN 33
J 2
(-3635 910);
DISPLAY 0.617021 (-3635 910);
PAINT MONO (-3635 910);
FORCEPROP 2 LASTPIN (-3625 1100) $PN 34
J 2
(-3635 1110);
DISPLAY 0.617021 (-3635 1110);
PAINT MONO (-3635 1110);
FORCEPROP 2 LASTPIN (-2625 1750) $PN 38
J 0
(-2615 1760);
DISPLAY 0.617021 (-2615 1760);
PAINT MONO (-2615 1760);
FORCEPROP 1 LAST LOCATION EU4D1
J 0
(-3575 2000);
DISPLAY 0.617021 (-3575 2000);
PAINT AQUA (-3575 2000);
FORCEPROP 1 LAST MATERIAL IC
J 0
(-3575 1950);
DISPLAY 0.617021 (-3575 1950);
PAINT SKYBLUE (-3575 1950);
FORCEPROP 2 LAST CDS_LOCATION EU4D1
J 0
(-3575 2000);
PAINT GREEN (-3575 2000);
DISPLAY INVISIBLE (-3575 2000);
FORCEPROP 1 LAST PATH I71
J 0
(-3125 1950);
PAINT GREEN (-3125 1950);
DISPLAY INVISIBLE (-3125 1950);
FORCEPROP 2 LAST CDS_LIB mstr_discrete
J 0
(-3125 1200);
PAINT ORANGE (-3125 1200);
DISPLAY INVISIBLE (-3125 1200);
FORCEPROP 2 LAST $SEC 1
J 0
(-3575 2050);
PAINT MONO (-3575 2050);
DISPLAY INVISIBLE (-3575 2050);
FORCEPROP 2 LAST CDS_SEC 1
J 0
(-3575 2050);
PAINT MONO (-3575 2050);
DISPLAY INVISIBLE (-3575 2050);
FORCEPROP 1 LAST PACK_TYPE SM
J 0
(-3575 2050);
PAINT SKYBLUE (-3575 2050);
DISPLAY INVISIBLE (-3575 2050);
FORCEPROP 1 LAST VALUE IR35411
J 1
(-3125 1825);
DISPLAY 0.617021 (-3125 1825);
PAINT SKYBLUE (-3125 1825);
DISPLAY INVISIBLE (-3125 1825);
FORCEADD RES..2
(-400 4100);
FORCEPROP 1 LAST LOCATION R4D72
J 0
(-355 4225);
DISPLAY 0.617021 (-355 4225);
PAINT AQUA (-355 4225);
FORCEPROP 1 LAST VALUE 68.1K
J 0
(-355 4175);
DISPLAY 0.617021 (-355 4175);
PAINT SKYBLUE (-355 4175);
FORCEPROP 1 LAST TOLERANCE 1%
J 0
(-355 4125);
DISPLAY 0.617021 (-355 4125);
PAINT SKYBLUE (-355 4125);
FORCEPROP 1 LAST WATTAGE 1/16W
J 0
(-360 4075);
DISPLAY 0.617021 (-360 4075);
PAINT SKYBLUE (-360 4075);
FORCEPROP 1 LAST MATERIAL EMPTY
J 0
(-360 4025);
DISPLAY 0.617021 (-360 4025);
PAINT RED (-360 4025);
FORCEPROP 1 LAST PART_NUMBER G21796-187
J 0
(-360 3975);
DISPLAY 0.617021 (-360 3975);
PAINT BLUE (-360 3975);
FORCEPROP 1 LAST PACK_TYPE 0402
J 0
(-360 3925);
DISPLAY 0.617021 (-360 3925);
PAINT SKYBLUE (-360 3925);
FORCEPROP 1 LASTPIN (-400 4000) $PN 2
J 0
(-395 4010);
DISPLAY 0.787234 (-395 4010);
PAINT ORANGE (-395 4010);
FORCEPROP 1 LASTPIN (-400 4200) $PN 1
J 0
(-395 4162);
DISPLAY 0.787234 (-395 4162);
PAINT ORANGE (-395 4162);
FORCEPROP 2 LAST SEC_TYPE 0402
J 0
(-350 4325);
DISPLAY 1.021277 (-350 4325);
PAINT ORANGE (-350 4325);
DISPLAY INVISIBLE (-350 4325);
FORCEPROP 2 LAST SEC 1
J 0
(-350 4325);
PAINT MONO (-350 4325);
DISPLAY INVISIBLE (-350 4325);
FORCEPROP 1 LAST PATH I89
J 0
(-350 4275);
DISPLAY 0.978723 (-350 4275);
PAINT WHITE (-350 4275);
DISPLAY INVISIBLE (-350 4275);
FORCEPROP 2 LAST CDS_LIB mstr_discrete
J 0
(-400 4100);
PAINT ORANGE (-400 4100);
DISPLAY INVISIBLE (-400 4100);
FORCEADD GND..1
(-400 3875);
FORCEPROP 3 LASTPIN (-400 3925) SIG_NAME GND\g
J 0
(-390 3935);
DISPLAY 0.659574 (-390 3935);
PAINT MONO (-390 3935);
DISPLAY INVISIBLE (-390 3935);
FORCEPROP 1 LAST HDL_POWER GND
J 0
(-400 4025);
DISPLAY 1.723404 (-400 4025);
PAINT GREEN (-400 4025);
DISPLAY INVISIBLE (-400 4025);
FORCEPROP 1 LAST BODY_TYPE PLUMBING
J 0
(-445 3832);
DISPLAY 0.340426 (-445 3832);
PAINT GREEN (-445 3832);
DISPLAY INVISIBLE (-445 3832);
FORCEPROP 1 LAST VOLTAGE 0
J 0
(-400 3875);
PAINT SKYBLUE (-400 3875);
DISPLAY INVISIBLE (-400 3875);
FORCEPROP 2 LAST CDS_LIB mstr_symbols
J 0
(-400 3875);
PAINT ORANGE (-400 3875);
DISPLAY INVISIBLE (-400 3875);
FORCEPROP 1 LAST PATH I90
J 0
(-325 3875);
DISPLAY 0.872340 (-325 3875);
PAINT AQUA (-325 3875);
DISPLAY INVISIBLE (-325 3875);
FORCEPROP 1 LAST SIZE 1B
J 0
(-325 3825);
DISPLAY 1.723404 (-325 3825);
PAINT GREEN (-325 3825);
DISPLAY INVISIBLE (-325 3825);
FORCEPROP 2 LAST BOM_COST PROC_VRD_VCCIN_CPU0
J 0
(-775 3950);
DISPLAY 1.446809 (-775 3950);
PAINT MONO (-775 3950);
DISPLAY INVISIBLE (-775 3950);
FORCEPROP 2 LAST ROOM PVCCIN_CPU0_PWR_VR
J 0
(-950 3950);
DISPLAY 1.936170 (-950 3950);
PAINT ORANGE (-950 3950);
DISPLAY INVISIBLE (-950 3950);
FORCEADD RES..2
(-375 1400);
FORCEPROP 1 LASTPIN (-375 1300) $PN 2
J 0
(-370 1310);
DISPLAY 0.787234 (-370 1310);
PAINT ORANGE (-370 1310);
FORCEPROP 1 LASTPIN (-375 1500) $PN 1
J 0
(-370 1462);
DISPLAY 0.787234 (-370 1462);
PAINT ORANGE (-370 1462);
FORCEPROP 1 LAST TOLERANCE 1%
J 0
(-330 1425);
DISPLAY 0.617021 (-330 1425);
PAINT SKYBLUE (-330 1425);
FORCEPROP 1 LAST PACK_TYPE 0402
J 0
(-335 1225);
DISPLAY 0.617021 (-335 1225);
PAINT SKYBLUE (-335 1225);
FORCEPROP 1 LAST MATERIAL EMPTY
J 0
(-335 1325);
DISPLAY 0.617021 (-335 1325);
PAINT RED (-335 1325);
FORCEPROP 1 LAST WATTAGE 1/16W
J 0
(-335 1375);
DISPLAY 0.617021 (-335 1375);
PAINT SKYBLUE (-335 1375);
FORCEPROP 1 LAST VALUE 68.1K
J 0
(-330 1475);
DISPLAY 0.617021 (-330 1475);
PAINT SKYBLUE (-330 1475);
FORCEPROP 1 LAST LOCATION R4D71
J 0
(-330 1525);
DISPLAY 0.617021 (-330 1525);
PAINT AQUA (-330 1525);
FORCEPROP 1 LAST PART_NUMBER G21796-187
J 0
(-335 1275);
DISPLAY 0.617021 (-335 1275);
PAINT BLUE (-335 1275);
FORCEPROP 2 LAST SEC_TYPE 0402
J 0
(-325 1625);
DISPLAY 1.021277 (-325 1625);
PAINT ORANGE (-325 1625);
DISPLAY INVISIBLE (-325 1625);
FORCEPROP 2 LAST SEC 1
J 0
(-325 1625);
PAINT MONO (-325 1625);
DISPLAY INVISIBLE (-325 1625);
FORCEPROP 2 LAST CDS_LIB mstr_discrete
J 0
(-375 1400);
PAINT ORANGE (-375 1400);
DISPLAY INVISIBLE (-375 1400);
FORCEPROP 1 LAST PATH I91
J 0
(-325 1575);
DISPLAY 0.978723 (-325 1575);
PAINT WHITE (-325 1575);
DISPLAY INVISIBLE (-325 1575);
FORCEADD GND..1
(-375 1225);
FORCEPROP 3 LASTPIN (-375 1275) SIG_NAME GND\g
J 0
(-365 1285);
DISPLAY 0.659574 (-365 1285);
PAINT MONO (-365 1285);
DISPLAY INVISIBLE (-365 1285);
FORCEPROP 1 LAST HDL_POWER GND
J 0
(-375 1375);
DISPLAY 1.723404 (-375 1375);
PAINT GREEN (-375 1375);
DISPLAY INVISIBLE (-375 1375);
FORCEPROP 1 LAST BODY_TYPE PLUMBING
J 0
(-420 1182);
DISPLAY 0.340426 (-420 1182);
PAINT GREEN (-420 1182);
DISPLAY INVISIBLE (-420 1182);
FORCEPROP 2 LAST BOM_COST PROC_VRD_VCCIN_CPU0
J 0
(-750 1300);
DISPLAY 1.446809 (-750 1300);
PAINT MONO (-750 1300);
DISPLAY INVISIBLE (-750 1300);
FORCEPROP 2 LAST ROOM PVCCIN_CPU0_PWR_VR
J 0
(-925 1300);
DISPLAY 1.936170 (-925 1300);
PAINT ORANGE (-925 1300);
DISPLAY INVISIBLE (-925 1300);
FORCEPROP 1 LAST VOLTAGE 0
J 0
(-375 1225);
PAINT SKYBLUE (-375 1225);
DISPLAY INVISIBLE (-375 1225);
FORCEPROP 2 LAST CDS_LIB mstr_symbols
J 0
(-375 1225);
PAINT ORANGE (-375 1225);
DISPLAY INVISIBLE (-375 1225);
FORCEPROP 1 LAST SIZE 1B
J 0
(-300 1175);
DISPLAY 1.723404 (-300 1175);
PAINT GREEN (-300 1175);
DISPLAY INVISIBLE (-300 1175);
FORCEPROP 1 LAST PATH I92
J 0
(-300 1225);
DISPLAY 0.872340 (-300 1225);
PAINT AQUA (-300 1225);
DISPLAY INVISIBLE (-300 1225);
FORCEADD CAP_A..1
(-3900 700);
FORCEPROP 1 LAST LOCATION CT40
J 0
(-4050 700);
DISPLAY 0.617021 (-4050 700);
PAINT AQUA (-4050 700);
FORCEPROP 1 LASTPIN (-3900 600) $PN 2
J 0
(-3890 580);
DISPLAY 0.787234 (-3890 580);
PAINT ORANGE (-3890 580);
FORCEPROP 1 LASTPIN (-3900 800) $PN 1
J 0
(-3890 780);
DISPLAY 0.787234 (-3890 780);
PAINT ORANGE (-3890 780);
FORCEPROP 1 LAST VOLTAGE 16V
J 0
(-3850 700);
DISPLAY 0.617021 (-3850 700);
PAINT SKYBLUE (-3850 700);
FORCEPROP 1 LAST VALUE 0.1UF
J 0
(-3850 750);
DISPLAY 0.617021 (-3850 750);
PAINT SKYBLUE (-3850 750);
FORCEPROP 1 LAST MATERIAL X7R
J 0
(-3850 600);
DISPLAY 0.617021 (-3850 600);
PAINT SKYBLUE (-3850 600);
FORCEPROP 1 LAST TOLERANCE 10%
J 0
(-3850 650);
DISPLAY 0.617021 (-3850 650);
PAINT SKYBLUE (-3850 650);
FORCEPROP 0 LAST POP NOPOP
J 0
(-3850 450);
DISPLAY 1.021277 (-3850 450);
PAINT RED (-3850 450);
FORCEPROP 1 LAST PACK_TYPE 0402V
J 0
(-3850 500);
DISPLAY 0.617021 (-3850 500);
PAINT SKYBLUE (-3850 500);
FORCEPROP 1 LAST PART_NUMBER A36096-030
J 0
(-3850 550);
DISPLAY 0.617021 (-3850 550);
PAINT BLUE (-3850 550);
FORCEPROP 2 LAST SEC_TYPE 0402V
J 0
(-3850 900);
DISPLAY 1.021277 (-3850 900);
PAINT ORANGE (-3850 900);
DISPLAY INVISIBLE (-3850 900);
FORCEPROP 0 LAST SEC 1
J 0
(-3850 800);
DISPLAY 0.680851 (-3850 800);
PAINT MONO (-3850 800);
DISPLAY INVISIBLE (-3850 800);
FORCEPROP 2 LAST CDS_LIB dev_discrete
J 0
(-3900 700);
PAINT MONO (-3900 700);
DISPLAY INVISIBLE (-3900 700);
FORCEPROP 1 LAST PATH I93
J 0
(-3850 850);
DISPLAY 0.978723 (-3850 850);
PAINT WHITE (-3850 850);
DISPLAY INVISIBLE (-3850 850);
FORCEPROP 2 LAST ROOM PVCCIN_CPU0_PWR_VR
J 0
(-3850 850);
DISPLAY 1.361702 (-3850 850);
PAINT ORANGE (-3850 850);
DISPLAY INVISIBLE (-3850 850);
FORCEADD GND..1
(-3900 425);
FORCEPROP 3 LASTPIN (-3900 475) SIG_NAME GND\g
J 0
(-3890 485);
DISPLAY 0.659574 (-3890 485);
PAINT MONO (-3890 485);
DISPLAY INVISIBLE (-3890 485);
FORCEPROP 1 LAST HDL_POWER GND
J 0
(-3900 575);
DISPLAY 1.723404 (-3900 575);
PAINT GREEN (-3900 575);
DISPLAY INVISIBLE (-3900 575);
FORCEPROP 1 LAST BODY_TYPE PLUMBING
J 0
(-3945 382);
DISPLAY 0.340426 (-3945 382);
PAINT GREEN (-3945 382);
DISPLAY INVISIBLE (-3945 382);
FORCEPROP 1 LAST VOLTAGE 0
J 0
(-3900 425);
PAINT SKYBLUE (-3900 425);
DISPLAY INVISIBLE (-3900 425);
FORCEPROP 1 LAST SIZE 1B
J 0
(-3825 375);
DISPLAY 1.723404 (-3825 375);
PAINT GREEN (-3825 375);
DISPLAY INVISIBLE (-3825 375);
FORCEPROP 2 LAST BOM_COST PROC_VRD_VCCIN_CPU0
J 0
(-4275 500);
DISPLAY 1.446809 (-4275 500);
PAINT MONO (-4275 500);
DISPLAY INVISIBLE (-4275 500);
FORCEPROP 2 LAST ROOM PVCCIN_CPU0_PWR_VR
J 0
(-4450 500);
DISPLAY 1.936170 (-4450 500);
PAINT ORANGE (-4450 500);
DISPLAY INVISIBLE (-4450 500);
FORCEPROP 1 LAST PATH I94
J 0
(-3825 425);
DISPLAY 0.872340 (-3825 425);
PAINT AQUA (-3825 425);
DISPLAY INVISIBLE (-3825 425);
FORCEPROP 2 LAST CDS_LIB mstr_symbols
J 0
(-3900 425);
PAINT MONO (-3900 425);
DISPLAY INVISIBLE (-3900 425);
FORCEADD CAP_A..1
(-3900 3400);
FORCEPROP 1 LAST MATERIAL X7R
J 0
(-3850 3300);
DISPLAY 0.617021 (-3850 3300);
PAINT SKYBLUE (-3850 3300);
FORCEPROP 1 LASTPIN (-3900 3500) $PN 1
J 0
(-3890 3480);
DISPLAY 0.787234 (-3890 3480);
PAINT ORANGE (-3890 3480);
FORCEPROP 0 LAST POP NOPOP
J 0
(-3850 3125);
DISPLAY 1.021277 (-3850 3125);
PAINT RED (-3850 3125);
FORCEPROP 1 LAST PACK_TYPE 0402V
J 0
(-3850 3200);
DISPLAY 0.617021 (-3850 3200);
PAINT SKYBLUE (-3850 3200);
FORCEPROP 1 LAST PART_NUMBER A36096-030
J 0
(-3850 3250);
DISPLAY 0.617021 (-3850 3250);
PAINT BLUE (-3850 3250);
FORCEPROP 1 LAST LOCATION CT39
J 0
(-4075 3400);
DISPLAY 0.617021 (-4075 3400);
PAINT AQUA (-4075 3400);
FORCEPROP 1 LASTPIN (-3900 3300) $PN 2
J 0
(-3890 3280);
DISPLAY 0.787234 (-3890 3280);
PAINT ORANGE (-3890 3280);
FORCEPROP 1 LAST TOLERANCE 10%
J 0
(-3850 3350);
DISPLAY 0.617021 (-3850 3350);
PAINT SKYBLUE (-3850 3350);
FORCEPROP 1 LAST VOLTAGE 16V
J 0
(-3850 3400);
DISPLAY 0.617021 (-3850 3400);
PAINT SKYBLUE (-3850 3400);
FORCEPROP 1 LAST VALUE 0.1UF
J 0
(-3850 3450);
DISPLAY 0.617021 (-3850 3450);
PAINT SKYBLUE (-3850 3450);
FORCEPROP 2 LAST SEC_TYPE 0402V
J 0
(-3850 3600);
DISPLAY 1.021277 (-3850 3600);
PAINT ORANGE (-3850 3600);
DISPLAY INVISIBLE (-3850 3600);
FORCEPROP 0 LAST SEC 1
J 0
(-3850 3500);
DISPLAY 0.680851 (-3850 3500);
PAINT MONO (-3850 3500);
DISPLAY INVISIBLE (-3850 3500);
FORCEPROP 2 LAST CDS_LIB dev_discrete
J 0
(-3900 3400);
PAINT MONO (-3900 3400);
DISPLAY INVISIBLE (-3900 3400);
FORCEPROP 1 LAST PATH I96
J 0
(-3850 3550);
DISPLAY 0.978723 (-3850 3550);
PAINT WHITE (-3850 3550);
DISPLAY INVISIBLE (-3850 3550);
FORCEPROP 2 LAST ROOM PVCCIN_CPU0_PWR_VR
J 0
(-3850 3550);
DISPLAY 1.361702 (-3850 3550);
PAINT ORANGE (-3850 3550);
DISPLAY INVISIBLE (-3850 3550);
FORCEADD GND..1
(-3900 3150);
FORCEPROP 3 LASTPIN (-3900 3200) SIG_NAME GND\g
J 0
(-3890 3210);
DISPLAY 0.659574 (-3890 3210);
PAINT MONO (-3890 3210);
DISPLAY INVISIBLE (-3890 3210);
FORCEPROP 1 LAST HDL_POWER GND
J 0
(-3900 3300);
DISPLAY 1.723404 (-3900 3300);
PAINT GREEN (-3900 3300);
DISPLAY INVISIBLE (-3900 3300);
FORCEPROP 1 LAST BODY_TYPE PLUMBING
J 0
(-3945 3107);
DISPLAY 0.340426 (-3945 3107);
PAINT GREEN (-3945 3107);
DISPLAY INVISIBLE (-3945 3107);
FORCEPROP 2 LAST CDS_LIB mstr_symbols
J 0
(-3900 3150);
PAINT MONO (-3900 3150);
DISPLAY INVISIBLE (-3900 3150);
FORCEPROP 1 LAST PATH I97
J 0
(-3825 3150);
DISPLAY 0.872340 (-3825 3150);
PAINT AQUA (-3825 3150);
DISPLAY INVISIBLE (-3825 3150);
FORCEPROP 2 LAST ROOM PVCCIN_CPU0_PWR_VR
J 0
(-4450 3225);
DISPLAY 1.936170 (-4450 3225);
PAINT ORANGE (-4450 3225);
DISPLAY INVISIBLE (-4450 3225);
FORCEPROP 2 LAST BOM_COST PROC_VRD_VCCIN_CPU0
J 0
(-4275 3225);
DISPLAY 1.446809 (-4275 3225);
PAINT MONO (-4275 3225);
DISPLAY INVISIBLE (-4275 3225);
FORCEPROP 1 LAST SIZE 1B
J 0
(-3825 3100);
DISPLAY 1.723404 (-3825 3100);
PAINT GREEN (-3825 3100);
DISPLAY INVISIBLE (-3825 3100);
FORCEPROP 1 LAST VOLTAGE 0
J 0
(-3900 3150);
PAINT SKYBLUE (-3900 3150);
DISPLAY INVISIBLE (-3900 3150);
FORCEADD CAP..1
(-1975 3950);
FORCEPROP 1 LASTPIN (-1975 3850) $PN 2
J 0
(-1965 3830);
DISPLAY 0.787234 (-1965 3830);
PAINT ORANGE (-1965 3830);
FORCEPROP 1 LAST MATERIAL X7R
J 0
(-1925 3850);
DISPLAY 0.617021 (-1925 3850);
PAINT SKYBLUE (-1925 3850);
FORCEPROP 1 LASTPIN (-1975 4050) $PN 1
J 0
(-1965 4030);
DISPLAY 0.787234 (-1965 4030);
PAINT ORANGE (-1965 4030);
FORCEPROP 1 LAST VALUE 1000PF
J 0
(-1925 4000);
DISPLAY 0.617021 (-1925 4000);
PAINT SKYBLUE (-1925 4000);
FORCEPROP 1 LAST VOLTAGE 50V
J 0
(-1925 3950);
DISPLAY 0.617021 (-1925 3950);
PAINT SKYBLUE (-1925 3950);
FORCEPROP 1 LAST TOLERANCE 10%
J 0
(-1925 3900);
DISPLAY 0.617021 (-1925 3900);
PAINT SKYBLUE (-1925 3900);
FORCEPROP 1 LAST LOCATION CT37
J 0
(-2125 3950);
DISPLAY 0.617021 (-2125 3950);
PAINT AQUA (-2125 3950);
FORCEPROP 1 LAST PART_NUMBER A36096-046
J 0
(-1925 3800);
DISPLAY 0.617021 (-1925 3800);
PAINT BLUE (-1925 3800);
FORCEPROP 1 LAST PACK_TYPE 0402LF
J 0
(-1925 3750);
DISPLAY 0.617021 (-1925 3750);
PAINT SKYBLUE (-1925 3750);
FORCEPROP 0 LAST POP NOPOP
J 0
(-2250 3875);
DISPLAY 1.021277 (-2250 3875);
PAINT RED (-2250 3875);
FORCEPROP 2 LAST SEC_TYPE 0402LF
J 0
(-1925 4150);
DISPLAY 1.021277 (-1925 4150);
PAINT ORANGE (-1925 4150);
DISPLAY INVISIBLE (-1925 4150);
FORCEPROP 0 LAST SEC 1
J 0
(-1925 4050);
DISPLAY 0.680851 (-1925 4050);
PAINT MONO (-1925 4050);
DISPLAY INVISIBLE (-1925 4050);
FORCEPROP 2 LAST CDS_LIB mstr_discrete
J 0
(-1975 3950);
PAINT MONO (-1975 3950);
DISPLAY INVISIBLE (-1975 3950);
FORCEPROP 1 LAST PATH I99
J 0
(-1925 4100);
DISPLAY 0.978723 (-1925 4100);
PAINT WHITE (-1925 4100);
DISPLAY INVISIBLE (-1925 4100);
FORCEPROP 0 LAST ROOM VDDQ_KLM_PWR_VR
J 0
(-1925 4150);
DISPLAY 1.021277 (-1925 4150);
PAINT ORANGE (-1925 4150);
DISPLAY INVISIBLE (-1925 4150);
FORCEADD INTEL_CORP_BPAGE..1
(0 0);
FORCEPROP 1 LAST CDS_CON_LAST_MODIFIED Fri Jun 16 17:49:14 2017
J 0
(-1425 325);
PAINT GREEN (-1425 325);
DISPLAY INVISIBLE (-1425 325);
FORCEPROP 1 LAST CUSTOM_TXT_CDS <CURRENT_DESIGN_SHEET> OF <TOTAL_DESIGN_SHEETS>
J 0
(-500 25);
PAINT ORANGE (-500 25);
FORCEPROP 2 LAST CUSTOM_TXT_CDS <XR_PAGE_TITLE>
J 0
(-7890 5250);
DISPLAY 0.638298 (-7890 5250);
PAINT PINK (-7890 5250);
DISPLAY INVISIBLE (-7890 5250);
FORCEPROP 2 LAST CUSTOM_TXT_CDS <CON_LAST_MODIFIED>
J 0
(-4000 100);
PAINT ORANGE (-4000 100);
FORCEPROP 1 LAST SCH_TITLE VCCIN CPU0 (3 OF 4)
J 0
(-7950 50);
DISPLAY 1.212766 (-7950 50);
PAINT GREEN (-7950 50);
FORCEPROP 1 LAST COMMENT_BODY TRUE
J 0
(12 12);
DISPLAY 0.468085 (12 12);
PAINT GREEN (12 12);
DISPLAY INVISIBLE (12 12);
FORCEPROP 2 LAST CDS_LIB mstr_symbols
J 0
(0 0);
PAINT ORANGE (0 0);
DISPLAY INVISIBLE (0 0);
FORCEPROP 2 LAST PAGE_BORDER TRUE
J 0
(-7890 5250);
DISPLAY 0.638298 (-7890 5250);
PAINT PINK (-7890 5250);
DISPLAY INVISIBLE (-7890 5250);
FORCEPROP 2 LAST CDS_XR_PAGE_TITLE CR-203 : @BASEBOARD_FAB2_LIB.BASEBOARD_FAB2(SCH_1):PAGE203
J 0
(-7890 5250);
DISPLAY 0.638298 (-7890 5250);
PAINT PINK (-7890 5250);
DISPLAY INVISIBLE (-7890 5250);
FORCEADD DNS..2
(-395 4095);
PAINT RED (-395 4095);
FORCEPROP 1 LAST COMMENT_BODY TRUE
R 1
J 0
(-320 3870);
DISPLAY 0.872340 (-320 3870);
PAINT GREEN (-320 3870);
DISPLAY INVISIBLE (-320 3870);
FORCEPROP 2 LAST CDS_LIB mstr_misc
J 0
(-395 4095);
PAINT ORANGE (-395 4095);
DISPLAY INVISIBLE (-395 4095);
FORCEADD DNS..2
(-370 1395);
PAINT RED (-370 1395);
FORCEPROP 1 LAST COMMENT_BODY TRUE
R 1
J 0
(-295 1170);
DISPLAY 0.872340 (-295 1170);
PAINT GREEN (-295 1170);
DISPLAY INVISIBLE (-295 1170);
FORCEPROP 2 LAST CDS_LIB mstr_misc
J 0
(-370 1395);
PAINT ORANGE (-370 1395);
DISPLAY INVISIBLE (-370 1395);
WIRE 16 -1 (-1975 3825)(-1975 3850);
WIRE 16 -1 (-1950 3050)(-1950 3075);
WIRE 16 -1 (-1975 425)(-1975 400);
WIRE 16 -1 (-1925 1175)(-1925 1125);
WIRE 16 -1 (-450 925)(-450 975);
WIRE 16 -1 (-700 925)(-450 925);
WIRE 16 -1 (-450 825)(-450 925);
WIRE 16 -1 (-900 925)(-700 925);
WIRE 16 -1 (-700 925)(-700 825);
WIRE 16 -1 (-900 325)(-900 925);
WIRE 16 -1 (-925 925)(-900 925);
WIRE 16 -1 (-3775 325)(-900 325);
WIRE 16 -1 (-3775 1350)(-3775 325);
WIRE 16 -1 (-3625 1350)(-3775 1350);
WIRE 16 -1 (-500 3650)(-500 3700);
WIRE 16 -1 (-800 3650)(-500 3650);
WIRE 16 -1 (-500 3650)(-500 3550);
WIRE 16 -1 (-800 3650)(-975 3650);
WIRE 16 -1 (-800 3550)(-800 3650);
WIRE 16 -1 (-975 2975)(-975 3650);
WIRE 16 -1 (-1025 3650)(-975 3650);
WIRE 16 -1 (-3750 2975)(-975 2975);
WIRE 16 -1 (-3750 4075)(-3750 2975);
WIRE 16 -1 (-3600 4075)(-3750 4075);
WIRE 16 -1 (-500 3150)(-500 3175);
WIRE 16 -1 (-500 3175)(-800 3175);
WIRE 16 -1 (-500 3350)(-500 3175);
WIRE 16 -1 (-800 3350)(-800 3175);
WIRE 16 -1 (-475 2350)(-475 2275);
WIRE 16 -1 (-925 2350)(-475 2350);
WIRE 16 -1 (-475 2450)(-475 2350);
WIRE 16 -1 (-1400 2350)(-925 2350);
WIRE 16 -1 (-925 2500)(-925 2350);
WIRE 16 -1 (-1400 2350)(-1850 2350);
WIRE 16 -1 (-1400 2500)(-1400 2350);
WIRE 16 -1 (-1850 2350)(-2300 2350);
WIRE 16 -1 (-1850 2500)(-1850 2350);
WIRE 16 -1 (-2300 2350)(-2750 2350);
WIRE 16 -1 (-2300 2500)(-2300 2350);
WIRE 16 -1 (-2750 2350)(-3200 2350);
WIRE 16 -1 (-2750 2500)(-2750 2350);
WIRE 16 -1 (-3200 2350)(-3625 2350);
WIRE 16 -1 (-3200 2500)(-3200 2350);
WIRE 16 -1 (-3625 2500)(-3625 2350);
WIRE 16 -1 (-700 475)(-700 500);
WIRE 16 -1 (-450 500)(-700 500);
WIRE 16 -1 (-700 500)(-700 625);
WIRE 16 -1 (-450 625)(-450 500);
WIRE 16 -1 (-2475 3325)(-2475 3375);
WIRE 16 -1 (-2475 3375)(-2475 3425);
WIRE 16 -1 (-2600 3375)(-2475 3375);
WIRE 16 -1 (-2475 3425)(-2475 3475);
WIRE 16 -1 (-2600 3425)(-2475 3425);
WIRE 16 -1 (-2475 3525)(-2475 3475);
WIRE 16 -1 (-2600 3475)(-2475 3475);
WIRE 16 -1 (-2600 3525)(-2475 3525);
WIRE 16 -1 (-3625 2775)(-3625 2825);
WIRE 16 -1 (-3200 2775)(-3625 2775);
WIRE 16 -1 (-3625 2700)(-3625 2775);
WIRE 16 -1 (-2750 2775)(-3200 2775);
WIRE 16 -1 (-3200 2700)(-3200 2775);
WIRE 16 -1 (-2300 2775)(-2750 2775);
WIRE 16 -1 (-2750 2700)(-2750 2775);
WIRE 16 -1 (-1850 2775)(-2300 2775);
WIRE 16 -1 (-2300 2700)(-2300 2775);
WIRE 16 -1 (-1400 2775)(-1850 2775);
WIRE 16 -1 (-1850 2700)(-1850 2775);
WIRE 16 -1 (-1400 2775)(-925 2775);
WIRE 16 -1 (-1400 2700)(-1400 2775);
WIRE 16 -1 (-475 2775)(-925 2775);
WIRE 16 -1 (-925 2700)(-925 2775);
WIRE 16 -1 (-475 2650)(-475 2775);
WIRE 16 -1 (-6550 4550)(-6550 4375);
WIRE 16 -1 (-6550 4375)(-6350 4375);
WIRE 16 -1 (-6700 4375)(-6550 4375);
WIRE 16 -1 (-7000 4375)(-6700 4375);
WIRE 16 -1 (-6700 4275)(-6700 4375);
WIRE 16 -1 (-6350 4375)(-6050 4375);
WIRE 16 -1 (-6350 4275)(-6350 4375);
WIRE 16 -1 (-6050 4375)(-5775 4375);
WIRE 16 -1 (-6050 4250)(-6050 4375);
WIRE 16 -1 (-7000 4275)(-7000 4375);
WIRE 16 -1 (-3850 4375)(-5775 4375);
WIRE 16 -1 (-5775 4250)(-5775 4375);
WIRE 16 -1 (-3850 4425)(-3850 4375);
WIRE 16 -1 (-3600 4375)(-3850 4375);
WIRE 16 -1 (-3600 4425)(-3850 4425);
WIRE 16 -1 (-7000 3775)(-7000 3875);
WIRE 16 -1 (-7000 3875)(-6700 3875);
WIRE 16 -1 (-7000 4075)(-7000 3875);
WIRE 16 -1 (-6700 3875)(-6350 3875);
WIRE 16 -1 (-6700 4075)(-6700 3875);
WIRE 16 -1 (-6350 3875)(-6050 3875);
WIRE 16 -1 (-6350 4075)(-6350 3875);
WIRE 16 -1 (-6050 3875)(-5775 3875);
WIRE 16 -1 (-6050 4050)(-6050 3875);
WIRE 16 -1 (-5475 3875)(-5775 3875);
WIRE 16 -1 (-5775 4050)(-5775 3875);
WIRE 16 -1 (-5050 3875)(-5475 3875);
WIRE 16 -1 (-5475 4050)(-5475 3875);
WIRE 16 -1 (-4600 3875)(-5050 3875);
WIRE 16 -1 (-5050 4075)(-5050 3875);
WIRE 16 -1 (-4600 4050)(-4600 3875);
WIRE 16 -1 (-6650 1850)(-6650 1700);
WIRE 16 -1 (-6650 1700)(-6550 1700);
WIRE 16 -1 (-6825 1700)(-6650 1700);
WIRE 16 -1 (-7100 1700)(-6825 1700);
WIRE 16 -1 (-6825 1575)(-6825 1700);
WIRE 16 -1 (-6250 1700)(-6550 1700);
WIRE 16 -1 (-6550 1575)(-6550 1700);
WIRE 16 -1 (-5975 1700)(-6250 1700);
WIRE 16 -1 (-6250 1575)(-6250 1700);
WIRE 16 -1 (-7100 1575)(-7100 1700);
WIRE 16 -1 (-3775 1700)(-5975 1700);
WIRE 16 -1 (-5975 1575)(-5975 1700);
WIRE 16 -1 (-3775 1700)(-3775 1650);
WIRE 16 -1 (-3625 1700)(-3775 1700);
WIRE 16 -1 (-3625 1650)(-3775 1650);
WIRE 16 -1 (-7100 1050)(-7100 1150);
WIRE 16 -1 (-7100 1150)(-6825 1150);
WIRE 16 -1 (-7100 1375)(-7100 1150);
WIRE 16 -1 (-6825 1150)(-6550 1150);
WIRE 16 -1 (-6825 1375)(-6825 1150);
WIRE 16 -1 (-6250 1150)(-6550 1150);
WIRE 16 -1 (-6550 1375)(-6550 1150);
WIRE 16 -1 (-5975 1150)(-6250 1150);
WIRE 16 -1 (-6250 1375)(-6250 1150);
WIRE 16 -1 (-5675 1150)(-5975 1150);
WIRE 16 -1 (-5975 1375)(-5975 1150);
WIRE 16 -1 (-5675 1150)(-5200 1150);
WIRE 16 -1 (-5675 1375)(-5675 1150);
WIRE 16 -1 (-4825 1150)(-5200 1150);
WIRE 16 -1 (-5200 1400)(-5200 1150);
WIRE 16 -1 (-4825 1375)(-4825 1150);
WIRE 16 -1 (-2550 575)(-2550 650);
WIRE 16 -1 (-2550 650)(-2550 700);
WIRE 16 -1 (-2550 650)(-2625 650);
WIRE 16 -1 (-2550 700)(-2550 750);
WIRE 16 -1 (-2550 700)(-2625 700);
WIRE 16 -1 (-2550 750)(-2550 800);
WIRE 16 -1 (-2550 750)(-2625 750);
WIRE 16 -1 (-2625 800)(-2550 800);
WIRE 16 -1 (-4400 4825)(-4400 4750);
WIRE 16 -1 (-4400 4750)(-4400 4275);
WIRE 16 -1 (-4400 4750)(-4600 4750);
WIRE 16 -1 (-4600 4750)(-5050 4750);
WIRE 16 -1 (-4600 4250)(-4600 4750);
WIRE 16 -1 (-3775 4275)(-4400 4275);
WIRE 16 -1 (-3775 4175)(-3775 4275);
WIRE 16 -1 (-3600 4275)(-3775 4275);
WIRE 16 -1 (-5050 4225)(-5050 4750);
WIRE 16 -1 (-5050 4750)(-5225 4750);
WIRE 16 -1 (-3600 4175)(-3775 4175);
WIRE 16 -1 (-4375 2075)(-4375 2000);
WIRE 16 -1 (-4375 2000)(-4375 1550);
WIRE 16 -1 (-4825 2000)(-4375 2000);
WIRE 16 -1 (-4825 2000)(-5200 2000);
WIRE 16 -1 (-4825 1575)(-4825 2000);
WIRE 16 -1 (-4375 1550)(-3750 1550);
WIRE 16 -1 (-3750 1450)(-3750 1550);
WIRE 16 -1 (-3750 1550)(-3625 1550);
WIRE 16 -1 (-5325 2000)(-5200 2000);
WIRE 16 -1 (-5200 1550)(-5200 2000);
WIRE 16 -1 (-3625 1450)(-3750 1450);
WIRE 16 -1 (-400 4000)(-400 3925);
WIRE 16 -1 (-375 1300)(-375 1275);
WIRE 16 -1 (-3900 475)(-3900 600);
WIRE 16 -1 (-3900 3300)(-3900 3200);
WIRE 16 2175 (-5150 3925)(-4500 3925);
WIRE 16 2175 (-4500 4325)(-4500 3925);
WIRE 16 2175 (-5150 4325)(-5150 3925);
WIRE 16 2175 (-5150 4325)(-4500 4325);
WIRE 16 -1 (-2625 1425)(-2625 1250);
WIRE 16 -1 (-2625 1425)(-1925 1425);
FORCEPROP 2 LAST SIG_NAME A_TSENSE_PVCCIN_CPU0
J 0
(-2612 1435);
DISPLAY 0.617021 (-2612 1435);
PAINT ORANGE (-2612 1435);
WIRE 16 -1 (-1925 1375)(-1925 1425);
WIRE 16 -1 (-1925 1425)(-1225 1425);
WIRE 16 -1 (-2625 1750)(-950 1750);
FORCEPROP 2 LAST SIG_NAME ISENSE_PVCCIN_CPU0_PH4_IMON
J 0
(-2415 1760);
DISPLAY 0.617021 (-2415 1760);
PAINT ORANGE (-2415 1760);
WIRE 16 -1 (-4000 3575)(-3600 3575);
WIRE 16 -1 (-5800 3450)(-4000 3450);
FORCEPROP 0 LAST VOLTAGE 5
J 0
(-5750 3525);
DISPLAY 1.021277 (-5750 3525);
PAINT SKYBLUE (-5750 3525);
DISPLAY INVISIBLE (-5750 3525);
FORCEPROP 2 LAST SIG_NAME VR_PVCCIN_CPU0_PH3_PHASE
J 0
(-5759 3463);
DISPLAY 0.617021 (-5759 3463);
PAINT ORANGE (-5759 3463);
FORCEPROP 2 LASTPROP $XRERR UNIQUE?
J 0
(-5999 3463);
DISPLAY 0.638298 (-5999 3463);
PAINT MONO (-5999 3463);
DISPLAY INVISIBLE (-5999 3463);
WIRE 16 -1 (-4000 3450)(-4000 3575);
WIRE 3 2175 (-5025 3800)(-4550 3800);
WIRE 3 2175 (-4550 3800)(-4550 3550);
WIRE 3 2175 (-5025 3800)(-5025 3550);
WIRE 3 2175 (-5025 3550)(-4550 3550);
WIRE 16 -1 (-5800 3725)(-5800 3650);
WIRE 16 -1 (-4825 3725)(-5800 3725);
FORCEPROP 2 LAST SIG_NAME VR_PVCCIN_CPU0_PH3_BOOT
J 0
(-5800 3738);
DISPLAY 0.617021 (-5800 3738);
PAINT ORANGE (-5800 3738);
FORCEPROP 2 LASTPROP $XRERR UNIQUE?
J 0
(-6040 3738);
DISPLAY 0.638298 (-6040 3738);
PAINT MONO (-6040 3738);
DISPLAY INVISIBLE (-6040 3738);
WIRE 16 -1 (-6525 3825)(-3600 3825);
WIRE 3 682 (-5000 4000)(-5100 4000);
WIRE 3 682 (-5000 4300)(-5000 4000);
WIRE 3 682 (-5100 4000)(-5100 4300);
WIRE 3 682 (-5100 4300)(-5000 4300);
WIRE 16 -1 (-3900 4850)(-850 4850);
FORCEPROP 2 LAST SIG_NAME VR_PVCCIN_CPU0_AIREF3
J 0
(-1429 4856);
DISPLAY 0.617021 (-1429 4856);
PAINT ORANGE (-1429 4856);
WIRE 16 -1 (-3900 3500)(-3900 3725);
WIRE 16 -1 (-3600 3725)(-3900 3725);
WIRE 16 -1 (-3900 3725)(-3900 4850);
WIRE 3 2175 (-2275 2950)(-1350 2950);
WIRE 3 2175 (-1350 3625)(-1350 2950);
WIRE 3 2175 (-2275 3625)(-2275 2950);
WIRE 3 2175 (-2275 3625)(-1350 3625);
WIRE 16 -1 (-3900 1000)(-3900 800);
WIRE 16 -1 (-3625 1000)(-3900 1000);
WIRE 16 -1 (-3900 2075)(-3900 1000);
WIRE 16 -1 (-1025 2075)(-3900 2075);
FORCEPROP 2 LAST SIG_NAME VR_PVCCIN_CPU0_AIREF4
J 0
(-1627 2083);
DISPLAY 0.617021 (-1627 2083);
PAINT ORANGE (-1627 2083);
WIRE 16 -1 (-375 1550)(-375 1500);
WIRE 16 -1 (-2625 1550)(-375 1550);
FORCEPROP 0 LAST VOLTAGE 3.6
J 0
(-2550 1625);
DISPLAY 1.021277 (-2550 1625);
PAINT SKYBLUE (-2550 1625);
DISPLAY INVISIBLE (-2550 1625);
FORCEPROP 2 LAST SIG_NAME VR_PVCCIN_CPU0_PH4_OCSET
J 0
(-2493 1566);
DISPLAY 0.617021 (-2493 1566);
PAINT ORANGE (-2493 1566);
FORCEPROP 2 LASTPROP $XRERR UNIQUE?
J 0
(-2733 1566);
DISPLAY 0.638298 (-2733 1566);
PAINT MONO (-2733 1566);
DISPLAY INVISIBLE (-2733 1566);
WIRE 3 2175 (-2175 1475)(-1625 1475);
WIRE 3 2175 (-1625 1475)(-1625 1050);
WIRE 3 2175 (-2175 1475)(-2175 1050);
WIRE 3 2175 (-2175 1050)(-1625 1050);
WIRE 16 -1 (-4450 1200)(-3625 1200);
FORCEPROP 0 LAST SIG_NAME TP_PVCCIN_CPU0_PH4_GL_0
J 0
(-4423 1215);
DISPLAY 0.617021 (-4423 1215);
PAINT ORANGE (-4423 1215);
FORCEPROP 2 LASTPROP $XRERR UNIQUE?
J 0
(-4690 1200);
DISPLAY 0.638298 (-4690 1200);
PAINT MONO (-4690 1200);
DISPLAY INVISIBLE (-4690 1200);
WIRE 16 -1 (-6500 1100)(-3625 1100);
FORCEPROP 2 LAST SIG_NAME VR_PVCCIN_CPU0_PWM4
J 0
(-6513 1110);
DISPLAY 0.617021 (-6513 1110);
PAINT ORANGE (-6513 1110);
WIRE 3 2175 (-2050 350)(-1250 350);
WIRE 3 2175 (-1250 950)(-1250 350);
WIRE 3 2175 (-2050 950)(-2050 350);
WIRE 3 2175 (-2050 950)(-1250 950);
WIRE 16 -1 (-2625 925)(-2625 900);
WIRE 16 -1 (-2625 925)(-1975 925);
FORCEPROP 0 LAST VOLTAGE 5
J 0
(-2200 1000);
DISPLAY 1.021277 (-2200 1000);
PAINT SKYBLUE (-2200 1000);
DISPLAY INVISIBLE (-2200 1000);
FORCEPROP 2 LAST SIG_NAME VR_PVCCIN_CPU0_PHASE4
J 0
(-2590 935);
DISPLAY 0.617021 (-2590 935);
PAINT ORANGE (-2590 935);
FORCEPROP 2 LASTPROP $XRERR UNIQUE?
J 0
(-2830 935);
DISPLAY 0.638298 (-2830 935);
PAINT MONO (-2830 935);
DISPLAY INVISIBLE (-2830 935);
WIRE 16 -1 (-1975 900)(-1975 925);
WIRE 16 -1 (-1225 925)(-1975 925);
WIRE 16 -1 (-1950 3325)(-1950 3375);
WIRE 16 -1 (-1950 3375)(-1950 3400);
WIRE 16 -1 (-1950 3375)(-1200 3375);
FORCEPROP 2 LAST SIG_NAME VR_PVCCIN_CPU0_PHASE3_RC
J 0
(-1840 3385);
DISPLAY 0.510638 (-1840 3385);
PAINT ORANGE (-1840 3385);
FORCEPROP 2 LASTPROP $XRERR UNIQUE?
J 0
(-1170 3375);
DISPLAY 0.638298 (-1170 3375);
PAINT MONO (-1170 3375);
DISPLAY INVISIBLE (-1170 3375);
WIRE 16 -1 (-400 4200)(-400 4275);
WIRE 16 -1 (-2600 4275)(-400 4275);
FORCEPROP 0 LAST VOLTAGE 3.6
J 0
(-2525 4350);
DISPLAY 1.021277 (-2525 4350);
PAINT SKYBLUE (-2525 4350);
DISPLAY INVISIBLE (-2525 4350);
FORCEPROP 2 LAST SIG_NAME VR_PVCCIN_CPU0_PH3_OCSET
J 0
(-2468 4291);
DISPLAY 0.617021 (-2468 4291);
PAINT ORANGE (-2468 4291);
FORCEPROP 2 LASTPROP $XRERR UNIQUE?
J 0
(-2708 4291);
DISPLAY 0.638298 (-2708 4291);
PAINT MONO (-2708 4291);
DISPLAY INVISIBLE (-2708 4291);
WIRE 16 -1 (-1950 3600)(-1950 3650);
WIRE 16 -1 (-1325 3650)(-1950 3650);
WIRE 16 -1 (-2600 3650)(-2600 3625);
WIRE 16 -1 (-2600 3650)(-1950 3650);
FORCEPROP 0 LAST VOLTAGE 5
J 0
(-2050 3725);
DISPLAY 1.021277 (-2050 3725);
PAINT SKYBLUE (-2050 3725);
DISPLAY INVISIBLE (-2050 3725);
FORCEPROP 2 LAST SIG_NAME VR_PVCCIN_CPU0_PHASE3
J 0
(-2415 3660);
DISPLAY 0.617021 (-2415 3660);
PAINT ORANGE (-2415 3660);
FORCEPROP 2 LASTPROP $XRERR UNIQUE?
J 0
(-2655 3660);
DISPLAY 0.638298 (-2655 3660);
PAINT MONO (-2655 3660);
DISPLAY INVISIBLE (-2655 3660);
WIRE 16 -1 (-4450 1250)(-3625 1250);
FORCEPROP 0 LAST SIG_NAME TP_PVCCIN_CPU0_PH4_GL_1
J 0
(-4423 1265);
DISPLAY 0.617021 (-4423 1265);
PAINT ORANGE (-4423 1265);
FORCEPROP 2 LASTPROP $XRERR UNIQUE?
J 0
(-4690 1250);
DISPLAY 0.638298 (-4690 1250);
PAINT MONO (-4690 1250);
DISPLAY INVISIBLE (-4690 1250);
WIRE 16 2175 (-5300 1675)(-4575 1675);
WIRE 16 2175 (-4575 1675)(-4575 1275);
WIRE 16 2175 (-5300 1675)(-5300 1275);
WIRE 16 2175 (-5300 1275)(-4575 1275);
WIRE 16 -1 (-5675 1575)(-5675 1750);
WIRE 16 -1 (-5675 1750)(-3625 1750);
FORCEPROP 0 LAST VOLTAGE 5
J 0
(-4225 1825);
DISPLAY 1.021277 (-4225 1825);
PAINT SKYBLUE (-4225 1825);
DISPLAY INVISIBLE (-4225 1825);
FORCEPROP 2 LAST SIG_NAME VR_PVCCIN_CPU0_PH4_VCIN
J 0
(-5639 1760);
DISPLAY 0.617021 (-5639 1760);
PAINT ORANGE (-5639 1760);
FORCEPROP 2 LASTPROP $XRERR UNIQUE?
J 0
(-5879 1760);
DISPLAY 0.638298 (-5879 1760);
PAINT MONO (-5879 1760);
DISPLAY INVISIBLE (-5879 1760);
WIRE 16 -1 (-5675 2000)(-5675 1750);
WIRE 16 -1 (-5675 2000)(-5525 2000);
WIRE 3 2175 (-5600 1850)(-5250 1850);
WIRE 3 2175 (-5250 2100)(-5250 1850);
WIRE 3 2175 (-5600 2100)(-5600 1850);
WIRE 3 2175 (-5600 2100)(-5250 2100);
WIRE 3 682 (-5150 1300)(-5250 1300);
WIRE 3 682 (-5250 1300)(-5250 1600);
WIRE 3 682 (-5150 1600)(-5150 1300);
WIRE 3 682 (-5150 1600)(-5250 1600);
WIRE 3 2175 (-5175 1050)(-4650 1050);
WIRE 3 2175 (-4650 1050)(-4650 800);
WIRE 3 2175 (-5175 1050)(-5175 800);
WIRE 3 2175 (-5175 800)(-4650 800);
WIRE 16 -1 (-3600 3625)(-4000 3625);
WIRE 16 -1 (-4000 3725)(-4000 3625);
WIRE 16 -1 (-4625 3725)(-4000 3725);
FORCEPROP 2 LAST SIG_NAME VR_PVCCIN_CPU0_PH3_BOOT_R
J 0
(-4525 3738);
DISPLAY 0.617021 (-4525 3738);
PAINT ORANGE (-4525 3738);
FORCEPROP 2 LASTPROP $XRERR UNIQUE?
J 0
(-4765 3738);
DISPLAY 0.638298 (-4765 3738);
PAINT MONO (-4765 3738);
DISPLAY INVISIBLE (-4765 3738);
WIRE 16 -1 (-5475 4475)(-5475 4250);
WIRE 16 -1 (-3600 4475)(-5475 4475);
WIRE 16 -1 (-5475 4750)(-5475 4475);
WIRE 16 -1 (-5475 4750)(-5425 4750);
FORCEPROP 2 LAST SIG_NAME VR_PVCCIN_CPU0_PH3_VCIN
J 0
(-5444 4485);
DISPLAY 0.617021 (-5444 4485);
PAINT ORANGE (-5444 4485);
FORCEPROP 2 LASTPROP $XRERR UNIQUE?
J 0
(-5684 4485);
DISPLAY 0.638298 (-5684 4485);
PAINT MONO (-5684 4485);
DISPLAY INVISIBLE (-5684 4485);
WIRE 3 2175 (-5500 4600)(-5150 4600);
WIRE 3 2175 (-5150 4875)(-5150 4600);
WIRE 3 2175 (-5500 4875)(-5500 4600);
WIRE 3 2175 (-5500 4875)(-5150 4875);
WIRE 16 2175 (-6075 3775)(-5225 3775);
WIRE 16 2175 (-5225 3775)(-5225 3350);
WIRE 16 2175 (-6075 3775)(-6075 3350);
WIRE 16 2175 (-6075 3350)(-5225 3350);
WIRE 16 -1 (-1975 675)(-1975 700);
WIRE 16 -1 (-1975 675)(-1300 675);
FORCEPROP 2 LAST SIG_NAME VR_PVCCIN_CPU0_PHASE4_RC
J 0
(-1865 685);
DISPLAY 0.510638 (-1865 685);
PAINT ORANGE (-1865 685);
FORCEPROP 2 LASTPROP $XRERR UNIQUE?
J 0
(-1270 675);
DISPLAY 0.638298 (-1270 675);
PAINT MONO (-1270 675);
DISPLAY INVISIBLE (-1270 675);
WIRE 16 -1 (-4075 900)(-3625 900);
WIRE 16 -1 (-4075 975)(-4075 900);
WIRE 16 -1 (-4850 975)(-4075 975);
FORCEPROP 2 LAST SIG_NAME VR_PVCCIN_CPU0_PH4_BOOT_R
J 0
(-4640 981);
DISPLAY 0.617021 (-4640 981);
PAINT ORANGE (-4640 981);
FORCEPROP 2 LASTPROP $XRERR UNIQUE?
J 0
(-4880 981);
DISPLAY 0.638298 (-4880 981);
PAINT MONO (-4880 981);
DISPLAY INVISIBLE (-4880 981);
WIRE 16 -1 (-4075 850)(-3625 850);
WIRE 16 -1 (-4075 725)(-4075 850);
WIRE 16 -1 (-5875 725)(-4075 725);
FORCEPROP 0 LAST VOLTAGE 5
J 0
(-5800 800);
DISPLAY 1.021277 (-5800 800);
PAINT SKYBLUE (-5800 800);
DISPLAY INVISIBLE (-5800 800);
FORCEPROP 2 LAST SIG_NAME VR_PVCCIN_CPU0_PH4_PHASE
J 0
(-5813 731);
DISPLAY 0.617021 (-5813 731);
PAINT ORANGE (-5813 731);
FORCEPROP 2 LASTPROP $XRERR UNIQUE?
J 0
(-6053 731);
DISPLAY 0.638298 (-6053 731);
PAINT MONO (-6053 731);
DISPLAY INVISIBLE (-6053 731);
WIRE 16 -1 (-4325 3925)(-3600 3925);
FORCEPROP 0 LAST SIG_NAME TP_PVCCIN_CPU0_PH3_GL_0
J 0
(-4298 3940);
DISPLAY 0.617021 (-4298 3940);
PAINT ORANGE (-4298 3940);
FORCEPROP 2 LASTPROP $XRERR UNIQUE?
J 0
(-4565 3925);
DISPLAY 0.638298 (-4565 3925);
PAINT MONO (-4565 3925);
DISPLAY INVISIBLE (-4565 3925);
WIRE 16 2175 (-6250 600)(-5275 600);
WIRE 16 2175 (-5275 1025)(-5275 600);
WIRE 16 2175 (-6250 1025)(-6250 600);
WIRE 16 2175 (-6250 1025)(-5275 1025);
WIRE 3 682 (-2550 1500)(-2450 1500);
WIRE 16 -1 (-4325 3975)(-3600 3975);
FORCEPROP 0 LAST SIG_NAME TP_PVCCIN_CPU0_PH3_GL_1
J 0
(-4298 3990);
DISPLAY 0.617021 (-4298 3990);
PAINT ORANGE (-4298 3990);
FORCEPROP 2 LASTPROP $XRERR UNIQUE?
J 0
(-4565 3975);
DISPLAY 0.638298 (-4565 3975);
PAINT MONO (-4565 3975);
DISPLAY INVISIBLE (-4565 3975);
WIRE 3 2175 (-2025 3700)(-1650 3700);
WIRE 3 2175 (-1650 4200)(-1650 3700);
WIRE 3 2175 (-2025 4200)(-2025 3700);
WIRE 3 2175 (-2025 4200)(-1650 4200);
WIRE 16 -1 (-1975 4050)(-1975 4100);
WIRE 16 -1 (-1975 4100)(-1525 4100);
WIRE 16 -1 (-2600 4100)(-2600 3975);
WIRE 16 -1 (-2600 4100)(-1975 4100);
FORCEPROP 2 LAST SIG_NAME A_TSENSE_PVCCIN_CPU0
J 0
(-2543 4113);
DISPLAY 0.617021 (-2543 4113);
PAINT ORANGE (-2543 4113);
WIRE 16 -1 (-5875 925)(-5875 975);
WIRE 16 -1 (-5875 975)(-5050 975);
FORCEPROP 2 LAST SIG_NAME VR_PVCCIN_CPU0_PH4_BOOT
J 0
(-5865 981);
DISPLAY 0.617021 (-5865 981);
PAINT ORANGE (-5865 981);
FORCEPROP 2 LASTPROP $XRERR UNIQUE?
J 0
(-6105 981);
DISPLAY 0.638298 (-6105 981);
PAINT MONO (-6105 981);
DISPLAY INVISIBLE (-6105 981);
WIRE 3 682 (-2500 4225)(-2400 4225);
WIRE 16 -1 (-2600 4475)(-825 4475);
FORCEPROP 2 LAST SIG_NAME ISENSE_PVCCIN_CPU0_PH3_IMON
J 0
(-2355 4489);
DISPLAY 0.617021 (-2355 4489);
PAINT ORANGE (-2355 4489);
DOT 1 (-700 500);
DOT 1 (-700 925);
DOT 1 (-450 925);
DOT 1 (-2550 750);
DOT 1 (-1975 925);
DOT 1 (-500 3175);
DOT 1 (-500 3650);
DOT 1 (-5475 4475);
DOT 1 (-5050 3875);
DOT 1 (-5050 4750);
DOT 1 (-975 3650);
DOT 1 (-2550 650);
DOT 1 (-3900 3725);
DOT 1 (-2550 700);
DOT 1 (-4600 4750);
DOT 1 (-3750 1550);
DOT 1 (-4825 2000);
DOT 1 (-1925 1425);
DOT 1 (-2300 2350);
DOT 1 (-6700 3875);
DOT 1 (-6700 4375);
DOT 1 (-6350 3875);
DOT 1 (-6350 4375);
DOT 1 (-6050 3875);
DOT 1 (-6050 4375);
DOT 1 (-5775 3875);
DOT 1 (-5775 4375);
DOT 1 (-5475 3875);
DOT 1 (-5975 1150);
DOT 1 (-5975 1700);
DOT 1 (-6250 1150);
DOT 1 (-6250 1700);
DOT 1 (-6550 1150);
DOT 1 (-6550 1700);
DOT 1 (-6825 1150);
DOT 1 (-6825 1700);
DOT 1 (-5675 1150);
DOT 1 (-1400 2775);
DOT 1 (-4375 2000);
DOT 1 (-7100 1150);
DOT 1 (-3775 4275);
DOT 1 (-3850 4375);
DOT 1 (-475 2350);
DOT 1 (-925 2775);
DOT 1 (-1975 4100);
DOT 1 (-1950 3650);
DOT 1 (-1950 3375);
DOT 1 (-2475 3475);
DOT 1 (-2475 3375);
DOT 1 (-2475 3425);
DOT 1 (-1850 2775);
DOT 1 (-2300 2775);
DOT 1 (-1850 2350);
DOT 1 (-2750 2775);
DOT 1 (-2750 2350);
DOT 1 (-3200 2775);
DOT 1 (-3625 2775);
DOT 1 (-3775 1700);
DOT 1 (-4400 4750);
DOT 1 (-3900 1000);
DOT 1 (-6550 4375);
DOT 1 (-7000 3875);
DOT 1 (-6650 1700);
DOT 1 (-1400 2350);
DOT 1 (-925 2350);
DOT 1 (-900 925);
DOT 1 (-5200 2000);
DOT 1 (-5200 1150);
DOT 1 (-5675 1750);
DOT 1 (-3200 2350);
DOT 1 (-800 3650);
FORCENOTE
TP FAB1 CHANGE PN L4D1 0122
(-1575 1025) 0;
DISPLAY LEFT (-1575 1025);
DISPLAY 1.021277 (-1575 1025);
PAINT RED (-1575 1025);
FORCENOTE
ROOM=PVCCIN_CPU0_PWR_VR
(-6980 3160) 0;
DISPLAY LEFT (-6980 3160);
DISPLAY 2.446809 (-6980 3160);
PAINT PURPLE (-6980 3160);
FORCENOTE
TP FAB1 CO-LAY WITH TI PARTS 11/16
(-5175 3325) 0;
DISPLAY LEFT (-5175 3325);
DISPLAY 0.851064 (-5175 3325);
PAINT RED (-5175 3325);
FORCENOTE
TP FAB1 CHANGE TO 0 OHM 0107
(-5750 2100) 0;
DISPLAY LEFT (-5750 2100);
DISPLAY 0.638298 (-5750 2100);
PAINT RED (-5750 2100);
FORCENOTE
TDA21470
(-3275 1800) 0;
DISPLAY LEFT (-3275 1800);
DISPLAY 1.021277 (-3275 1800);
PAINT SKYBLUE (-3275 1800);
FORCENOTE
TP FAB1 CO-LAY WITH TI PARTS 11/16
(-1575 1175) 0;
DISPLAY LEFT (-1575 1175);
DISPLAY 1.021277 (-1575 1175);
PAINT RED (-1575 1175);
FORCENOTE
PLACE ON TOP
(-5155 3850) 0;
DISPLAY LEFT (-5155 3850);
DISPLAY 1.553191 (-5155 3850);
PAINT PURPLE (-5155 3850);
FORCENOTE
TDA21470
(-3250 4550) 0;
DISPLAY LEFT (-3250 4550);
DISPLAY 1.021277 (-3250 4550);
PAINT SKYBLUE (-3250 4550);
FORCENOTE
TP FAB1 CHANGE PN 0310
(-5225 1700) 0;
DISPLAY LEFT (-5225 1700);
DISPLAY 1.021277 (-5225 1700);
PAINT RED (-5225 1700);
FORCENOTE
TP FAB1 CO-LAY WITH TI PARTS 11/16
(-3175 450) 0;
DISPLAY LEFT (-3175 450);
DISPLAY 0.851064 (-3175 450);
PAINT RED (-3175 450);
FORCENOTE
TP FAB1 ADD NET NAME 12/04
(-1600 375) 0;
DISPLAY LEFT (-1600 375);
DISPLAY 0.680851 (-1600 375);
PAINT RED (-1600 375);
FORCENOTE
TP FAB1 DEL NET 0309
(-2400 1500) 0;
DISPLAY LEFT (-2400 1500);
DISPLAY 1.021277 (-2400 1500);
PAINT RED (-2400 1500);
FORCENOTE
TP FAB1 CHANGE PN 0310
(-5125 4400) 0;
DISPLAY LEFT (-5125 4400);
DISPLAY 1.021277 (-5125 4400);
PAINT RED (-5125 4400);
FORCENOTE
TP FAB1 CO-LAY WITH TI PARTS 11/16
(-5150 550) 0;
DISPLAY LEFT (-5150 550);
DISPLAY 0.851064 (-5150 550);
PAINT RED (-5150 550);
FORCENOTE
ROOM=PVCCIN_CPU0_PWR_VR
(-7480 310) 0;
DISPLAY LEFT (-7480 310);
DISPLAY 2.446809 (-7480 310);
PAINT PURPLE (-7480 310);
FORCENOTE
TP FAB1 DEL NET 0309
(-2375 4200) 0;
DISPLAY LEFT (-2375 4200);
DISPLAY 1.021277 (-2375 4200);
PAINT RED (-2375 4200);
FORCENOTE
SPOF
(-5780 525) 0;
DISPLAY LEFT (-5780 525);
DISPLAY 1.808511 (-5780 525);
PAINT PURPLE (-5780 525);
FORCENOTE
TP FAB1 CHANGE TO 0 OHM 0107
(-5425 4900) 0;
DISPLAY LEFT (-5425 4900);
DISPLAY 0.638298 (-5425 4900);
PAINT RED (-5425 4900);
FORCENOTE
TP FAB1 CHANGE RES TO 1 OHM 0603 0107
(-1750 300) 0;
DISPLAY LEFT (-1750 300);
DISPLAY 0.808511 (-1750 300);
PAINT RED (-1750 300);
FORCENOTE
PLACE ON TOP
(-5280 1175) 0;
DISPLAY LEFT (-5280 1175);
DISPLAY 1.553191 (-5280 1175);
PAINT PURPLE (-5280 1175);
FORCENOTE
ROOM = PVCCIN_CPU0_DECAP_VR
(-3165 2790) 0;
DISPLAY LEFT (-3165 2790);
DISPLAY 1.191489 (-3165 2790);
PAINT PURPLE (-3165 2790);
FORCENOTE
TP FAB1 CHANGE L4D2 PN 0122
(-1625 3825) 0;
DISPLAY LEFT (-1625 3825);
DISPLAY 1.021277 (-1625 3825);
PAINT RED (-1625 3825);
FORCENOTE
TP FAB1 CO-LAY WITH TI PARTS 11/16
(-1625 3875) 0;
DISPLAY LEFT (-1625 3875);
DISPLAY 1.021277 (-1625 3875);
PAINT RED (-1625 3875);
FORCENOTE
TP FAB1 CO-LAY WITH TI PARTS 11/16
(-1775 2850) 0;
DISPLAY LEFT (-1775 2850);
DISPLAY 0.638298 (-1775 2850);
PAINT RED (-1775 2850);
FORCENOTE
TP FAB1 CHANGE RES TO 1 OHM 0603 0107
(-1775 2900) 0;
DISPLAY LEFT (-1775 2900);
DISPLAY 0.638298 (-1775 2900);
PAINT RED (-1775 2900);
FORCENOTE
TP FAB1 ADD NET NAME 12/04
(-1325 3000) 0;
DISPLAY LEFT (-1325 3000);
DISPLAY 0.680851 (-1325 3000);
PAINT RED (-1325 3000);
FORCENOTE
SPOF
(-5855 3250) 0;
DISPLAY LEFT (-5855 3250);
DISPLAY 1.936170 (-5855 3250);
PAINT PURPLE (-5855 3250);
QUIT
